(kicad_sch
	(version 20250114)
	(generator "eeschema")
	(generator_version "9.0")
	(paper "A3")
	(title_block
		(title "SDI-MIPI Video Converter")
		(date "2023-10-12")
		(rev "1.1.4")
		(comment 1 "www.antmicro.com")
		(comment 2 "Antmicro Ltd.")
	)
	(text "FPGA"
		(exclude_from_sim no)
		(at 80.01 20.32 0)
		(effects
			(font
				(size 4 4)
			)
			(justify left bottom)
		)
	)
	(text "TERMINATION\n"
		(exclude_from_sim no)
		(at 214.63 181.61 0)
		(effects
			(font
				(size 4 4)
			)
			(justify left bottom)
		)
	)
	(text "RAM"
		(exclude_from_sim no)
		(at 276.86 20.32 0)
		(effects
			(font
				(size 4 4)
			)
			(justify left bottom)
		)
	)
	(text "Signal terminations can be\nrearanged for easier routing"
		(exclude_from_sim no)
		(at 220.98 264.16 0)
		(effects
			(font
				(size 1.27 1.27)
			)
			(justify left bottom)
		)
	)
	(junction
		(at 95.25 78.74)
		(diameter 0)
		(color 0 0 0 0)
	)
	(junction
		(at 132.08 38.1)
		(diameter 0)
		(color 0 0 0 0)
	)
	(junction
		(at 273.05 247.65)
		(diameter 0)
		(color 0 0 0 0)
	)
	(junction
		(at 307.34 78.74)
		(diameter 0)
		(color 0 0 0 0)
	)
	(junction
		(at 229.87 228.6)
		(diameter 0)
		(color 0 0 0 0)
	)
	(junction
		(at 346.71 91.44)
		(diameter 0)
		(color 0 0 0 0)
	)
	(junction
		(at 137.16 156.21)
		(diameter 0)
		(color 0 0 0 0)
	)
	(junction
		(at 328.93 78.74)
		(diameter 0)
		(color 0 0 0 0)
	)
	(junction
		(at 95.25 116.84)
		(diameter 0)
		(color 0 0 0 0)
	)
	(junction
		(at 95.25 222.25)
		(diameter 0)
		(color 0 0 0 0)
	)
	(junction
		(at 313.69 111.76)
		(diameter 0)
		(color 0 0 0 0)
	)
	(junction
		(at 229.87 250.19)
		(diameter 0)
		(color 0 0 0 0)
	)
	(junction
		(at 120.65 35.56)
		(diameter 0)
		(color 0 0 0 0)
	)
	(junction
		(at 130.81 38.1)
		(diameter 0)
		(color 0 0 0 0)
	)
	(junction
		(at 273.05 207.01)
		(diameter 0)
		(color 0 0 0 0)
	)
	(junction
		(at 341.63 85.09)
		(diameter 0)
		(color 0 0 0 0)
	)
	(junction
		(at 229.87 252.73)
		(diameter 0)
		(color 0 0 0 0)
	)
	(junction
		(at 295.91 54.61)
		(diameter 0)
		(color 0 0 0 0)
	)
	(junction
		(at 229.87 231.14)
		(diameter 0)
		(color 0 0 0 0)
	)
	(junction
		(at 318.77 54.61)
		(diameter 0)
		(color 0 0 0 0)
	)
	(junction
		(at 95.25 101.6)
		(diameter 0)
		(color 0 0 0 0)
	)
	(junction
		(at 307.34 54.61)
		(diameter 0)
		(color 0 0 0 0)
	)
	(junction
		(at 273.05 252.73)
		(diameter 0)
		(color 0 0 0 0)
	)
	(junction
		(at 229.87 204.47)
		(diameter 0)
		(color 0 0 0 0)
	)
	(junction
		(at 229.87 226.06)
		(diameter 0)
		(color 0 0 0 0)
	)
	(junction
		(at 314.96 111.76)
		(diameter 0)
		(color 0 0 0 0)
	)
	(junction
		(at 125.73 153.67)
		(diameter 0)
		(color 0 0 0 0)
	)
	(junction
		(at 115.57 153.67)
		(diameter 0)
		(color 0 0 0 0)
	)
	(junction
		(at 190.5 78.74)
		(diameter 0)
		(color 0 0 0 0)
	)
	(junction
		(at 273.05 204.47)
		(diameter 0)
		(color 0 0 0 0)
	)
	(junction
		(at 273.05 228.6)
		(diameter 0)
		(color 0 0 0 0)
	)
	(junction
		(at 273.05 209.55)
		(diameter 0)
		(color 0 0 0 0)
	)
	(junction
		(at 328.93 54.61)
		(diameter 0)
		(color 0 0 0 0)
	)
	(junction
		(at 95.25 66.04)
		(diameter 0)
		(color 0 0 0 0)
	)
	(junction
		(at 95.25 227.33)
		(diameter 0)
		(color 0 0 0 0)
	)
	(junction
		(at 95.25 35.56)
		(diameter 0)
		(color 0 0 0 0)
	)
	(junction
		(at 95.25 214.63)
		(diameter 0)
		(color 0 0 0 0)
	)
	(junction
		(at 229.87 247.65)
		(diameter 0)
		(color 0 0 0 0)
	)
	(junction
		(at 295.91 78.74)
		(diameter 0)
		(color 0 0 0 0)
	)
	(junction
		(at 229.87 209.55)
		(diameter 0)
		(color 0 0 0 0)
	)
	(junction
		(at 273.05 226.06)
		(diameter 0)
		(color 0 0 0 0)
	)
	(junction
		(at 138.43 156.21)
		(diameter 0)
		(color 0 0 0 0)
	)
	(junction
		(at 273.05 231.14)
		(diameter 0)
		(color 0 0 0 0)
	)
	(junction
		(at 95.25 153.67)
		(diameter 0)
		(color 0 0 0 0)
	)
	(junction
		(at 330.2 111.76)
		(diameter 0)
		(color 0 0 0 0)
	)
	(junction
		(at 95.25 212.09)
		(diameter 0)
		(color 0 0 0 0)
	)
	(junction
		(at 229.87 207.01)
		(diameter 0)
		(color 0 0 0 0)
	)
	(junction
		(at 95.25 91.44)
		(diameter 0)
		(color 0 0 0 0)
	)
	(junction
		(at 95.25 63.5)
		(diameter 0)
		(color 0 0 0 0)
	)
	(junction
		(at 190.5 88.9)
		(diameter 0)
		(color 0 0 0 0)
	)
	(junction
		(at 318.77 78.74)
		(diameter 0)
		(color 0 0 0 0)
	)
	(junction
		(at 328.93 111.76)
		(diameter 0)
		(color 0 0 0 0)
	)
	(junction
		(at 273.05 250.19)
		(diameter 0)
		(color 0 0 0 0)
	)
	(wire
		(pts
			(xy 229.87 204.47) (xy 229.87 207.01)
		)
		(stroke
			(width 0)
			(type default)
		)
	)
	(wire
		(pts
			(xy 92.71 232.41) (xy 110.49 232.41)
		)
		(stroke
			(width 0)
			(type default)
		)
	)
	(wire
		(pts
			(xy 203.2 123.19) (xy 214.63 123.19)
		)
		(stroke
			(width 0)
			(type default)
		)
	)
	(wire
		(pts
			(xy 196.85 228.6) (xy 209.55 228.6)
		)
		(stroke
			(width 0)
			(type default)
		)
	)
	(wire
		(pts
			(xy 264.16 77.47) (xy 250.19 77.47)
		)
		(stroke
			(width 0)
			(type default)
		)
	)
	(wire
		(pts
			(xy 262.89 209.55) (xy 273.05 209.55)
		)
		(stroke
			(width 0)
			(type default)
		)
	)
	(wire
		(pts
			(xy 262.89 233.68) (xy 273.05 233.68)
		)
		(stroke
			(width 0)
			(type default)
		)
	)
	(wire
		(pts
			(xy 262.89 207.01) (xy 273.05 207.01)
		)
		(stroke
			(width 0)
			(type default)
		)
	)
	(wire
		(pts
			(xy 110.49 86.36) (xy 92.71 86.36)
		)
		(stroke
			(width 0)
			(type default)
		)
	)
	(wire
		(pts
			(xy 262.89 212.09) (xy 273.05 212.09)
		)
		(stroke
			(width 0)
			(type default)
		)
	)
	(wire
		(pts
			(xy 177.8 78.74) (xy 190.5 78.74)
		)
		(stroke
			(width 0)
			(type default)
		)
	)
	(wire
		(pts
			(xy 273.05 200.66) (xy 273.05 204.47)
		)
		(stroke
			(width 0)
			(type default)
		)
	)
	(wire
		(pts
			(xy 203.2 74.93) (xy 214.63 74.93)
		)
		(stroke
			(width 0)
			(type default)
		)
	)
	(wire
		(pts
			(xy 95.25 101.6) (xy 92.71 101.6)
		)
		(stroke
			(width 0)
			(type default)
		)
	)
	(wire
		(pts
			(xy 95.25 78.74) (xy 95.25 66.04)
		)
		(stroke
			(width 0)
			(type default)
		)
	)
	(wire
		(pts
			(xy 264.16 100.33) (xy 250.19 100.33)
		)
		(stroke
			(width 0)
			(type default)
		)
	)
	(wire
		(pts
			(xy 219.71 204.47) (xy 229.87 204.47)
		)
		(stroke
			(width 0)
			(type default)
		)
	)
	(wire
		(pts
			(xy 95.25 212.09) (xy 95.25 214.63)
		)
		(stroke
			(width 0)
			(type default)
		)
	)
	(wire
		(pts
			(xy 95.25 43.18) (xy 92.71 43.18)
		)
		(stroke
			(width 0)
			(type default)
		)
	)
	(wire
		(pts
			(xy 203.2 118.11) (xy 214.63 118.11)
		)
		(stroke
			(width 0)
			(type default)
		)
	)
	(wire
		(pts
			(xy 328.93 111.76) (xy 330.2 111.76)
		)
		(stroke
			(width 0)
			(type default)
		)
	)
	(wire
		(pts
			(xy 318.77 54.61) (xy 307.34 54.61)
		)
		(stroke
			(width 0)
			(type default)
		)
	)
	(wire
		(pts
			(xy 92.71 234.95) (xy 110.49 234.95)
		)
		(stroke
			(width 0)
			(type default)
		)
	)
	(wire
		(pts
			(xy 229.87 207.01) (xy 229.87 209.55)
		)
		(stroke
			(width 0)
			(type default)
		)
	)
	(wire
		(pts
			(xy 219.71 247.65) (xy 229.87 247.65)
		)
		(stroke
			(width 0)
			(type default)
		)
	)
	(wire
		(pts
			(xy 95.25 222.25) (xy 95.25 227.33)
		)
		(stroke
			(width 0)
			(type default)
		)
	)
	(wire
		(pts
			(xy 307.34 78.74) (xy 295.91 78.74)
		)
		(stroke
			(width 0)
			(type default)
		)
	)
	(wire
		(pts
			(xy 196.85 255.27) (xy 209.55 255.27)
		)
		(stroke
			(width 0)
			(type default)
		)
	)
	(wire
		(pts
			(xy 295.91 77.47) (xy 295.91 78.74)
		)
		(stroke
			(width 0)
			(type default)
		)
	)
	(wire
		(pts
			(xy 341.63 85.09) (xy 347.98 85.09)
		)
		(stroke
			(width 0)
			(type default)
		)
	)
	(wire
		(pts
			(xy 341.63 85.09) (xy 341.63 82.55)
		)
		(stroke
			(width 0)
			(type default)
		)
	)
	(wire
		(pts
			(xy 110.49 88.9) (xy 92.71 88.9)
		)
		(stroke
			(width 0)
			(type default)
		)
	)
	(wire
		(pts
			(xy 92.71 184.15) (xy 110.49 184.15)
		)
		(stroke
			(width 0)
			(type default)
		)
	)
	(wire
		(pts
			(xy 92.71 189.23) (xy 110.49 189.23)
		)
		(stroke
			(width 0)
			(type default)
		)
	)
	(polyline
		(pts
			(xy 165.1 12.7) (xy 165.1 284.48)
		)
		(stroke
			(width 0)
			(type default)
		)
	)
	(wire
		(pts
			(xy 92.71 227.33) (xy 95.25 227.33)
		)
		(stroke
			(width 0)
			(type default)
		)
	)
	(wire
		(pts
			(xy 132.08 38.1) (xy 130.81 38.1)
		)
		(stroke
			(width 0)
			(type default)
		)
	)
	(wire
		(pts
			(xy 229.87 255.27) (xy 229.87 252.73)
		)
		(stroke
			(width 0)
			(type default)
		)
	)
	(wire
		(pts
			(xy 95.25 116.84) (xy 92.71 116.84)
		)
		(stroke
			(width 0)
			(type default)
		)
	)
	(wire
		(pts
			(xy 264.16 72.39) (xy 250.19 72.39)
		)
		(stroke
			(width 0)
			(type default)
		)
	)
	(wire
		(pts
			(xy 95.25 227.33) (xy 95.25 237.49)
		)
		(stroke
			(width 0)
			(type default)
		)
	)
	(wire
		(pts
			(xy 203.2 107.95) (xy 214.63 107.95)
		)
		(stroke
			(width 0)
			(type default)
		)
	)
	(wire
		(pts
			(xy 199.39 82.55) (xy 214.63 82.55)
		)
		(stroke
			(width 0)
			(type default)
		)
	)
	(wire
		(pts
			(xy 346.71 91.44) (xy 347.98 91.44)
		)
		(stroke
			(width 0)
			(type default)
		)
	)
	(wire
		(pts
			(xy 273.05 207.01) (xy 273.05 204.47)
		)
		(stroke
			(width 0)
			(type default)
		)
	)
	(wire
		(pts
			(xy 229.87 252.73) (xy 229.87 250.19)
		)
		(stroke
			(width 0)
			(type default)
		)
	)
	(wire
		(pts
			(xy 110.49 81.28) (xy 92.71 81.28)
		)
		(stroke
			(width 0)
			(type default)
		)
	)
	(wire
		(pts
			(xy 328.93 86.36) (xy 328.93 87.63)
		)
		(stroke
			(width 0)
			(type default)
		)
	)
	(wire
		(pts
			(xy 130.81 35.56) (xy 130.81 38.1)
		)
		(stroke
			(width 0)
			(type default)
		)
	)
	(polyline
		(pts
			(xy 407.67 156.21) (xy 407.67 154.94)
		)
		(stroke
			(width 0)
			(type default)
		)
	)
	(wire
		(pts
			(xy 137.16 156.21) (xy 138.43 156.21)
		)
		(stroke
			(width 0)
			(type default)
		)
	)
	(wire
		(pts
			(xy 92.71 163.83) (xy 110.49 163.83)
		)
		(stroke
			(width 0)
			(type default)
		)
	)
	(wire
		(pts
			(xy 328.93 119.38) (xy 328.93 120.65)
		)
		(stroke
			(width 0)
			(type default)
		)
	)
	(wire
		(pts
			(xy 308.61 111.76) (xy 313.69 111.76)
		)
		(stroke
			(width 0)
			(type default)
		)
	)
	(wire
		(pts
			(xy 203.2 95.25) (xy 214.63 95.25)
		)
		(stroke
			(width 0)
			(type default)
		)
	)
	(wire
		(pts
			(xy 330.2 102.87) (xy 330.2 104.14)
		)
		(stroke
			(width 0)
			(type default)
		)
	)
	(wire
		(pts
			(xy 313.69 119.38) (xy 313.69 120.65)
		)
		(stroke
			(width 0)
			(type default)
		)
	)
	(wire
		(pts
			(xy 341.63 82.55) (xy 347.98 82.55)
		)
		(stroke
			(width 0)
			(type default)
		)
	)
	(wire
		(pts
			(xy 203.2 72.39) (xy 214.63 72.39)
		)
		(stroke
			(width 0)
			(type default)
		)
	)
	(wire
		(pts
			(xy 240.03 252.73) (xy 252.73 252.73)
		)
		(stroke
			(width 0)
			(type default)
		)
	)
	(wire
		(pts
			(xy 264.16 95.25) (xy 250.19 95.25)
		)
		(stroke
			(width 0)
			(type default)
		)
	)
	(wire
		(pts
			(xy 264.16 82.55) (xy 250.19 82.55)
		)
		(stroke
			(width 0)
			(type default)
		)
	)
	(wire
		(pts
			(xy 92.71 219.71) (xy 110.49 219.71)
		)
		(stroke
			(width 0)
			(type default)
		)
	)
	(wire
		(pts
			(xy 330.2 109.22) (xy 330.2 111.76)
		)
		(stroke
			(width 0)
			(type default)
		)
	)
	(wire
		(pts
			(xy 219.71 207.01) (xy 229.87 207.01)
		)
		(stroke
			(width 0)
			(type default)
		)
	)
	(wire
		(pts
			(xy 95.25 179.07) (xy 95.25 212.09)
		)
		(stroke
			(width 0)
			(type default)
		)
	)
	(wire
		(pts
			(xy 92.71 181.61) (xy 110.49 181.61)
		)
		(stroke
			(width 0)
			(type default)
		)
	)
	(wire
		(pts
			(xy 120.65 35.56) (xy 95.25 35.56)
		)
		(stroke
			(width 0)
			(type default)
		)
	)
	(wire
		(pts
			(xy 203.2 133.35) (xy 214.63 133.35)
		)
		(stroke
			(width 0)
			(type default)
		)
	)
	(wire
		(pts
			(xy 190.5 78.74) (xy 190.5 81.28)
		)
		(stroke
			(width 0)
			(type default)
		)
	)
	(wire
		(pts
			(xy 196.85 250.19) (xy 209.55 250.19)
		)
		(stroke
			(width 0)
			(type default)
		)
	)
	(wire
		(pts
			(xy 120.65 35.56) (xy 120.65 41.91)
		)
		(stroke
			(width 0)
			(type default)
		)
	)
	(wire
		(pts
			(xy 341.63 85.09) (xy 341.63 111.76)
		)
		(stroke
			(width 0)
			(type default)
		)
	)
	(wire
		(pts
			(xy 110.49 48.26) (xy 92.71 48.26)
		)
		(stroke
			(width 0)
			(type default)
		)
	)
	(wire
		(pts
			(xy 264.16 90.17) (xy 250.19 90.17)
		)
		(stroke
			(width 0)
			(type default)
		)
	)
	(wire
		(pts
			(xy 264.16 62.23) (xy 250.19 62.23)
		)
		(stroke
			(width 0)
			(type default)
		)
	)
	(wire
		(pts
			(xy 110.49 111.76) (xy 92.71 111.76)
		)
		(stroke
			(width 0)
			(type default)
		)
	)
	(wire
		(pts
			(xy 110.49 83.82) (xy 92.71 83.82)
		)
		(stroke
			(width 0)
			(type default)
		)
	)
	(wire
		(pts
			(xy 196.85 209.55) (xy 209.55 209.55)
		)
		(stroke
			(width 0)
			(type default)
		)
	)
	(wire
		(pts
			(xy 273.05 255.27) (xy 273.05 252.73)
		)
		(stroke
			(width 0)
			(type default)
		)
	)
	(polyline
		(pts
			(xy 299.72 156.21) (xy 299.72 251.46)
		)
		(stroke
			(width 0)
			(type default)
		)
	)
	(wire
		(pts
			(xy 92.71 199.39) (xy 110.49 199.39)
		)
		(stroke
			(width 0)
			(type default)
		)
	)
	(wire
		(pts
			(xy 110.49 50.8) (xy 92.71 50.8)
		)
		(stroke
			(width 0)
			(type default)
		)
	)
	(wire
		(pts
			(xy 307.34 86.36) (xy 307.34 87.63)
		)
		(stroke
			(width 0)
			(type default)
		)
	)
	(wire
		(pts
			(xy 229.87 200.66) (xy 229.87 204.47)
		)
		(stroke
			(width 0)
			(type default)
		)
	)
	(wire
		(pts
			(xy 328.93 54.61) (xy 328.93 57.15)
		)
		(stroke
			(width 0)
			(type default)
		)
	)
	(wire
		(pts
			(xy 95.25 66.04) (xy 92.71 66.04)
		)
		(stroke
			(width 0)
			(type default)
		)
	)
	(wire
		(pts
			(xy 203.2 130.81) (xy 214.63 130.81)
		)
		(stroke
			(width 0)
			(type default)
		)
	)
	(wire
		(pts
			(xy 295.91 86.36) (xy 295.91 87.63)
		)
		(stroke
			(width 0)
			(type default)
		)
	)
	(wire
		(pts
			(xy 95.25 43.18) (xy 95.25 63.5)
		)
		(stroke
			(width 0)
			(type default)
		)
	)
	(wire
		(pts
			(xy 314.96 102.87) (xy 314.96 104.14)
		)
		(stroke
			(width 0)
			(type default)
		)
	)
	(wire
		(pts
			(xy 251.46 113.03) (xy 251.46 114.3)
		)
		(stroke
			(width 0)
			(type default)
		)
	)
	(wire
		(pts
			(xy 295.91 78.74) (xy 295.91 81.28)
		)
		(stroke
			(width 0)
			(type default)
		)
	)
	(wire
		(pts
			(xy 313.69 111.76) (xy 313.69 114.3)
		)
		(stroke
			(width 0)
			(type default)
		)
	)
	(wire
		(pts
			(xy 92.71 171.45) (xy 110.49 171.45)
		)
		(stroke
			(width 0)
			(type default)
		)
	)
	(wire
		(pts
			(xy 92.71 166.37) (xy 110.49 166.37)
		)
		(stroke
			(width 0)
			(type default)
		)
	)
	(wire
		(pts
			(xy 199.39 85.09) (xy 214.63 85.09)
		)
		(stroke
			(width 0)
			(type default)
		)
	)
	(wire
		(pts
			(xy 196.85 212.09) (xy 209.55 212.09)
		)
		(stroke
			(width 0)
			(type default)
		)
	)
	(wire
		(pts
			(xy 120.65 34.29) (xy 120.65 35.56)
		)
		(stroke
			(width 0)
			(type default)
		)
	)
	(wire
		(pts
			(xy 92.71 217.17) (xy 110.49 217.17)
		)
		(stroke
			(width 0)
			(type default)
		)
	)
	(wire
		(pts
			(xy 95.25 101.6) (xy 95.25 91.44)
		)
		(stroke
			(width 0)
			(type default)
		)
	)
	(wire
		(pts
			(xy 240.03 250.19) (xy 252.73 250.19)
		)
		(stroke
			(width 0)
			(type default)
		)
	)
	(wire
		(pts
			(xy 203.2 120.65) (xy 214.63 120.65)
		)
		(stroke
			(width 0)
			(type default)
		)
	)
	(wire
		(pts
			(xy 229.87 222.25) (xy 229.87 226.06)
		)
		(stroke
			(width 0)
			(type default)
		)
	)
	(wire
		(pts
			(xy 92.71 161.29) (xy 110.49 161.29)
		)
		(stroke
			(width 0)
			(type default)
		)
	)
	(wire
		(pts
			(xy 110.49 45.72) (xy 92.71 45.72)
		)
		(stroke
			(width 0)
			(type default)
		)
	)
	(wire
		(pts
			(xy 314.96 111.76) (xy 328.93 111.76)
		)
		(stroke
			(width 0)
			(type default)
		)
	)
	(wire
		(pts
			(xy 196.85 207.01) (xy 209.55 207.01)
		)
		(stroke
			(width 0)
			(type default)
		)
	)
	(wire
		(pts
			(xy 120.65 46.99) (xy 120.65 48.26)
		)
		(stroke
			(width 0)
			(type default)
		)
	)
	(wire
		(pts
			(xy 264.16 67.31) (xy 250.19 67.31)
		)
		(stroke
			(width 0)
			(type default)
		)
	)
	(wire
		(pts
			(xy 115.57 163.83) (xy 115.57 165.1)
		)
		(stroke
			(width 0)
			(type default)
		)
	)
	(wire
		(pts
			(xy 95.25 63.5) (xy 95.25 66.04)
		)
		(stroke
			(width 0)
			(type default)
		)
	)
	(wire
		(pts
			(xy 318.77 78.74) (xy 318.77 81.28)
		)
		(stroke
			(width 0)
			(type default)
		)
	)
	(wire
		(pts
			(xy 240.03 233.68) (xy 252.73 233.68)
		)
		(stroke
			(width 0)
			(type default)
		)
	)
	(wire
		(pts
			(xy 110.49 114.3) (xy 92.71 114.3)
		)
		(stroke
			(width 0)
			(type default)
		)
	)
	(wire
		(pts
			(xy 262.89 204.47) (xy 273.05 204.47)
		)
		(stroke
			(width 0)
			(type default)
		)
	)
	(wire
		(pts
			(xy 240.03 247.65) (xy 252.73 247.65)
		)
		(stroke
			(width 0)
			(type default)
		)
	)
	(wire
		(pts
			(xy 219.71 255.27) (xy 229.87 255.27)
		)
		(stroke
			(width 0)
			(type default)
		)
	)
	(wire
		(pts
			(xy 110.49 99.06) (xy 92.71 99.06)
		)
		(stroke
			(width 0)
			(type default)
		)
	)
	(wire
		(pts
			(xy 203.2 102.87) (xy 214.63 102.87)
		)
		(stroke
			(width 0)
			(type default)
		)
	)
	(wire
		(pts
			(xy 110.49 96.52) (xy 92.71 96.52)
		)
		(stroke
			(width 0)
			(type default)
		)
	)
	(wire
		(pts
			(xy 328.93 54.61) (xy 318.77 54.61)
		)
		(stroke
			(width 0)
			(type default)
		)
	)
	(wire
		(pts
			(xy 262.89 228.6) (xy 273.05 228.6)
		)
		(stroke
			(width 0)
			(type default)
		)
	)
	(wire
		(pts
			(xy 137.16 38.1) (xy 132.08 38.1)
		)
		(stroke
			(width 0)
			(type default)
		)
	)
	(wire
		(pts
			(xy 273.05 209.55) (xy 273.05 207.01)
		)
		(stroke
			(width 0)
			(type default)
		)
	)
	(wire
		(pts
			(xy 262.89 247.65) (xy 273.05 247.65)
		)
		(stroke
			(width 0)
			(type default)
		)
	)
	(wire
		(pts
			(xy 203.2 88.9) (xy 214.63 88.9)
		)
		(stroke
			(width 0)
			(type default)
		)
	)
	(wire
		(pts
			(xy 203.2 115.57) (xy 214.63 115.57)
		)
		(stroke
			(width 0)
			(type default)
		)
	)
	(wire
		(pts
			(xy 92.71 156.21) (xy 137.16 156.21)
		)
		(stroke
			(width 0)
			(type default)
		)
	)
	(wire
		(pts
			(xy 240.03 228.6) (xy 252.73 228.6)
		)
		(stroke
			(width 0)
			(type default)
		)
	)
	(wire
		(pts
			(xy 196.85 247.65) (xy 209.55 247.65)
		)
		(stroke
			(width 0)
			(type default)
		)
	)
	(wire
		(pts
			(xy 229.87 250.19) (xy 229.87 247.65)
		)
		(stroke
			(width 0)
			(type default)
		)
	)
	(wire
		(pts
			(xy 328.93 78.74) (xy 328.93 81.28)
		)
		(stroke
			(width 0)
			(type default)
		)
	)
	(wire
		(pts
			(xy 125.73 163.83) (xy 125.73 165.1)
		)
		(stroke
			(width 0)
			(type default)
		)
	)
	(wire
		(pts
			(xy 115.57 153.67) (xy 125.73 153.67)
		)
		(stroke
			(width 0)
			(type default)
		)
	)
	(wire
		(pts
			(xy 341.63 76.2) (xy 347.98 76.2)
		)
		(stroke
			(width 0)
			(type default)
		)
	)
	(wire
		(pts
			(xy 132.08 45.72) (xy 132.08 46.99)
		)
		(stroke
			(width 0)
			(type default)
		)
	)
	(wire
		(pts
			(xy 240.03 226.06) (xy 252.73 226.06)
		)
		(stroke
			(width 0)
			(type default)
		)
	)
	(wire
		(pts
			(xy 203.2 100.33) (xy 214.63 100.33)
		)
		(stroke
			(width 0)
			(type default)
		)
	)
	(wire
		(pts
			(xy 92.71 214.63) (xy 95.25 214.63)
		)
		(stroke
			(width 0)
			(type default)
		)
	)
	(wire
		(pts
			(xy 95.25 116.84) (xy 95.25 101.6)
		)
		(stroke
			(width 0)
			(type default)
		)
	)
	(wire
		(pts
			(xy 219.71 233.68) (xy 229.87 233.68)
		)
		(stroke
			(width 0)
			(type default)
		)
	)
	(wire
		(pts
			(xy 95.25 120.65) (xy 95.25 116.84)
		)
		(stroke
			(width 0)
			(type default)
		)
	)
	(wire
		(pts
			(xy 295.91 53.34) (xy 295.91 54.61)
		)
		(stroke
			(width 0)
			(type default)
		)
	)
	(wire
		(pts
			(xy 92.71 212.09) (xy 95.25 212.09)
		)
		(stroke
			(width 0)
			(type default)
		)
	)
	(wire
		(pts
			(xy 295.91 54.61) (xy 295.91 57.15)
		)
		(stroke
			(width 0)
			(type default)
		)
	)
	(wire
		(pts
			(xy 95.25 153.67) (xy 115.57 153.67)
		)
		(stroke
			(width 0)
			(type default)
		)
	)
	(wire
		(pts
			(xy 196.85 226.06) (xy 209.55 226.06)
		)
		(stroke
			(width 0)
			(type default)
		)
	)
	(wire
		(pts
			(xy 262.89 250.19) (xy 273.05 250.19)
		)
		(stroke
			(width 0)
			(type default)
		)
	)
	(wire
		(pts
			(xy 110.49 58.42) (xy 92.71 58.42)
		)
		(stroke
			(width 0)
			(type default)
		)
	)
	(wire
		(pts
			(xy 92.71 176.53) (xy 110.49 176.53)
		)
		(stroke
			(width 0)
			(type default)
		)
	)
	(wire
		(pts
			(xy 264.16 54.61) (xy 250.19 54.61)
		)
		(stroke
			(width 0)
			(type default)
		)
	)
	(wire
		(pts
			(xy 229.87 209.55) (xy 229.87 212.09)
		)
		(stroke
			(width 0)
			(type default)
		)
	)
	(wire
		(pts
			(xy 328.93 62.23) (xy 328.93 63.5)
		)
		(stroke
			(width 0)
			(type default)
		)
	)
	(wire
		(pts
			(xy 307.34 62.23) (xy 307.34 63.5)
		)
		(stroke
			(width 0)
			(type default)
		)
	)
	(wire
		(pts
			(xy 110.49 68.58) (xy 92.71 68.58)
		)
		(stroke
			(width 0)
			(type default)
		)
	)
	(wire
		(pts
			(xy 196.85 233.68) (xy 209.55 233.68)
		)
		(stroke
			(width 0)
			(type default)
		)
	)
	(wire
		(pts
			(xy 92.71 168.91) (xy 110.49 168.91)
		)
		(stroke
			(width 0)
			(type default)
		)
	)
	(wire
		(pts
			(xy 219.71 209.55) (xy 229.87 209.55)
		)
		(stroke
			(width 0)
			(type default)
		)
	)
	(wire
		(pts
			(xy 110.49 106.68) (xy 92.71 106.68)
		)
		(stroke
			(width 0)
			(type default)
		)
	)
	(wire
		(pts
			(xy 137.16 147.32) (xy 137.16 148.59)
		)
		(stroke
			(width 0)
			(type default)
		)
	)
	(wire
		(pts
			(xy 95.25 91.44) (xy 95.25 78.74)
		)
		(stroke
			(width 0)
			(type default)
		)
	)
	(wire
		(pts
			(xy 203.2 69.85) (xy 214.63 69.85)
		)
		(stroke
			(width 0)
			(type default)
		)
	)
	(wire
		(pts
			(xy 92.71 158.75) (xy 95.25 158.75)
		)
		(stroke
			(width 0)
			(type default)
		)
	)
	(wire
		(pts
			(xy 264.16 59.69) (xy 250.19 59.69)
		)
		(stroke
			(width 0)
			(type default)
		)
	)
	(wire
		(pts
			(xy 250.19 113.03) (xy 251.46 113.03)
		)
		(stroke
			(width 0)
			(type default)
		)
	)
	(wire
		(pts
			(xy 273.05 228.6) (xy 273.05 226.06)
		)
		(stroke
			(width 0)
			(type default)
		)
	)
	(wire
		(pts
			(xy 229.87 231.14) (xy 229.87 228.6)
		)
		(stroke
			(width 0)
			(type default)
		)
	)
	(wire
		(pts
			(xy 318.77 54.61) (xy 318.77 57.15)
		)
		(stroke
			(width 0)
			(type default)
		)
	)
	(wire
		(pts
			(xy 92.71 209.55) (xy 110.49 209.55)
		)
		(stroke
			(width 0)
			(type default)
		)
	)
	(wire
		(pts
			(xy 318.77 78.74) (xy 307.34 78.74)
		)
		(stroke
			(width 0)
			(type default)
		)
	)
	(wire
		(pts
			(xy 199.39 88.9) (xy 199.39 85.09)
		)
		(stroke
			(width 0)
			(type default)
		)
	)
	(wire
		(pts
			(xy 92.71 194.31) (xy 110.49 194.31)
		)
		(stroke
			(width 0)
			(type default)
		)
	)
	(wire
		(pts
			(xy 203.2 105.41) (xy 214.63 105.41)
		)
		(stroke
			(width 0)
			(type default)
		)
	)
	(wire
		(pts
			(xy 262.89 252.73) (xy 273.05 252.73)
		)
		(stroke
			(width 0)
			(type default)
		)
	)
	(wire
		(pts
			(xy 229.87 243.84) (xy 229.87 247.65)
		)
		(stroke
			(width 0)
			(type default)
		)
	)
	(wire
		(pts
			(xy 137.16 153.67) (xy 137.16 156.21)
		)
		(stroke
			(width 0)
			(type default)
		)
	)
	(wire
		(pts
			(xy 92.71 191.77) (xy 110.49 191.77)
		)
		(stroke
			(width 0)
			(type default)
		)
	)
	(wire
		(pts
			(xy 92.71 229.87) (xy 110.49 229.87)
		)
		(stroke
			(width 0)
			(type default)
		)
	)
	(wire
		(pts
			(xy 125.73 153.67) (xy 125.73 158.75)
		)
		(stroke
			(width 0)
			(type default)
		)
	)
	(wire
		(pts
			(xy 95.25 91.44) (xy 92.71 91.44)
		)
		(stroke
			(width 0)
			(type default)
		)
	)
	(wire
		(pts
			(xy 219.71 250.19) (xy 229.87 250.19)
		)
		(stroke
			(width 0)
			(type default)
		)
	)
	(wire
		(pts
			(xy 203.2 92.71) (xy 214.63 92.71)
		)
		(stroke
			(width 0)
			(type default)
		)
	)
	(wire
		(pts
			(xy 203.2 113.03) (xy 214.63 113.03)
		)
		(stroke
			(width 0)
			(type default)
		)
	)
	(wire
		(pts
			(xy 264.16 105.41) (xy 250.19 105.41)
		)
		(stroke
			(width 0)
			(type default)
		)
	)
	(wire
		(pts
			(xy 273.05 250.19) (xy 273.05 247.65)
		)
		(stroke
			(width 0)
			(type default)
		)
	)
	(wire
		(pts
			(xy 95.25 35.56) (xy 95.25 40.64)
		)
		(stroke
			(width 0)
			(type default)
		)
	)
	(wire
		(pts
			(xy 240.03 204.47) (xy 252.73 204.47)
		)
		(stroke
			(width 0)
			(type default)
		)
	)
	(wire
		(pts
			(xy 125.73 152.4) (xy 125.73 153.67)
		)
		(stroke
			(width 0)
			(type default)
		)
	)
	(wire
		(pts
			(xy 110.49 76.2) (xy 92.71 76.2)
		)
		(stroke
			(width 0)
			(type default)
		)
	)
	(wire
		(pts
			(xy 92.71 179.07) (xy 95.25 179.07)
		)
		(stroke
			(width 0)
			(type default)
		)
	)
	(polyline
		(pts
			(xy 165.1 156.21) (xy 407.67 156.21)
		)
		(stroke
			(width 0)
			(type default)
		)
	)
	(wire
		(pts
			(xy 95.25 78.74) (xy 92.71 78.74)
		)
		(stroke
			(width 0)
			(type default)
		)
	)
	(wire
		(pts
			(xy 138.43 163.83) (xy 138.43 165.1)
		)
		(stroke
			(width 0)
			(type default)
		)
	)
	(wire
		(pts
			(xy 92.71 186.69) (xy 110.49 186.69)
		)
		(stroke
			(width 0)
			(type default)
		)
	)
	(wire
		(pts
			(xy 251.46 119.38) (xy 251.46 120.65)
		)
		(stroke
			(width 0)
			(type default)
		)
	)
	(wire
		(pts
			(xy 240.03 231.14) (xy 252.73 231.14)
		)
		(stroke
			(width 0)
			(type default)
		)
	)
	(wire
		(pts
			(xy 203.2 80.01) (xy 214.63 80.01)
		)
		(stroke
			(width 0)
			(type default)
		)
	)
	(wire
		(pts
			(xy 307.34 54.61) (xy 307.34 57.15)
		)
		(stroke
			(width 0)
			(type default)
		)
	)
	(wire
		(pts
			(xy 132.08 38.1) (xy 132.08 40.64)
		)
		(stroke
			(width 0)
			(type default)
		)
	)
	(wire
		(pts
			(xy 196.85 252.73) (xy 209.55 252.73)
		)
		(stroke
			(width 0)
			(type default)
		)
	)
	(wire
		(pts
			(xy 199.39 82.55) (xy 199.39 78.74)
		)
		(stroke
			(width 0)
			(type default)
		)
	)
	(wire
		(pts
			(xy 95.25 63.5) (xy 92.71 63.5)
		)
		(stroke
			(width 0)
			(type default)
		)
	)
	(wire
		(pts
			(xy 92.71 207.01) (xy 110.49 207.01)
		)
		(stroke
			(width 0)
			(type default)
		)
	)
	(wire
		(pts
			(xy 262.89 226.06) (xy 273.05 226.06)
		)
		(stroke
			(width 0)
			(type default)
		)
	)
	(wire
		(pts
			(xy 264.16 85.09) (xy 250.19 85.09)
		)
		(stroke
			(width 0)
			(type default)
		)
	)
	(wire
		(pts
			(xy 219.71 231.14) (xy 229.87 231.14)
		)
		(stroke
			(width 0)
			(type default)
		)
	)
	(wire
		(pts
			(xy 229.87 228.6) (xy 229.87 226.06)
		)
		(stroke
			(width 0)
			(type default)
		)
	)
	(wire
		(pts
			(xy 137.16 34.29) (xy 137.16 38.1)
		)
		(stroke
			(width 0)
			(type default)
		)
	)
	(wire
		(pts
			(xy 307.34 78.74) (xy 307.34 81.28)
		)
		(stroke
			(width 0)
			(type default)
		)
	)
	(wire
		(pts
			(xy 148.59 152.4) (xy 148.59 156.21)
		)
		(stroke
			(width 0)
			(type default)
		)
	)
	(wire
		(pts
			(xy 273.05 243.84) (xy 273.05 247.65)
		)
		(stroke
			(width 0)
			(type default)
		)
	)
	(wire
		(pts
			(xy 199.39 78.74) (xy 190.5 78.74)
		)
		(stroke
			(width 0)
			(type default)
		)
	)
	(wire
		(pts
			(xy 219.71 226.06) (xy 229.87 226.06)
		)
		(stroke
			(width 0)
			(type default)
		)
	)
	(wire
		(pts
			(xy 273.05 252.73) (xy 273.05 250.19)
		)
		(stroke
			(width 0)
			(type default)
		)
	)
	(wire
		(pts
			(xy 346.71 95.25) (xy 346.71 91.44)
		)
		(stroke
			(width 0)
			(type default)
		)
	)
	(wire
		(pts
			(xy 341.63 54.61) (xy 341.63 76.2)
		)
		(stroke
			(width 0)
			(type default)
		)
	)
	(wire
		(pts
			(xy 148.59 156.21) (xy 138.43 156.21)
		)
		(stroke
			(width 0)
			(type default)
		)
	)
	(wire
		(pts
			(xy 328.93 78.74) (xy 318.77 78.74)
		)
		(stroke
			(width 0)
			(type default)
		)
	)
	(wire
		(pts
			(xy 110.49 71.12) (xy 92.71 71.12)
		)
		(stroke
			(width 0)
			(type default)
		)
	)
	(wire
		(pts
			(xy 273.05 222.25) (xy 273.05 226.06)
		)
		(stroke
			(width 0)
			(type default)
		)
	)
	(wire
		(pts
			(xy 264.16 69.85) (xy 250.19 69.85)
		)
		(stroke
			(width 0)
			(type default)
		)
	)
	(wire
		(pts
			(xy 330.2 111.76) (xy 341.63 111.76)
		)
		(stroke
			(width 0)
			(type default)
		)
	)
	(wire
		(pts
			(xy 308.61 107.95) (xy 308.61 111.76)
		)
		(stroke
			(width 0)
			(type default)
		)
	)
	(wire
		(pts
			(xy 203.2 128.27) (xy 214.63 128.27)
		)
		(stroke
			(width 0)
			(type default)
		)
	)
	(wire
		(pts
			(xy 110.49 55.88) (xy 92.71 55.88)
		)
		(stroke
			(width 0)
			(type default)
		)
	)
	(wire
		(pts
			(xy 130.81 38.1) (xy 92.71 38.1)
		)
		(stroke
			(width 0)
			(type default)
		)
	)
	(wire
		(pts
			(xy 203.2 57.15) (xy 214.63 57.15)
		)
		(stroke
			(width 0)
			(type default)
		)
	)
	(wire
		(pts
			(xy 203.2 59.69) (xy 214.63 59.69)
		)
		(stroke
			(width 0)
			(type default)
		)
	)
	(wire
		(pts
			(xy 95.25 153.67) (xy 92.71 153.67)
		)
		(stroke
			(width 0)
			(type default)
		)
	)
	(wire
		(pts
			(xy 110.49 53.34) (xy 92.71 53.34)
		)
		(stroke
			(width 0)
			(type default)
		)
	)
	(wire
		(pts
			(xy 92.71 224.79) (xy 110.49 224.79)
		)
		(stroke
			(width 0)
			(type default)
		)
	)
	(wire
		(pts
			(xy 138.43 156.21) (xy 138.43 158.75)
		)
		(stroke
			(width 0)
			(type default)
		)
	)
	(wire
		(pts
			(xy 318.77 86.36) (xy 318.77 87.63)
		)
		(stroke
			(width 0)
			(type default)
		)
	)
	(wire
		(pts
			(xy 273.05 231.14) (xy 273.05 228.6)
		)
		(stroke
			(width 0)
			(type default)
		)
	)
	(wire
		(pts
			(xy 219.71 212.09) (xy 229.87 212.09)
		)
		(stroke
			(width 0)
			(type default)
		)
	)
	(wire
		(pts
			(xy 318.77 62.23) (xy 318.77 63.5)
		)
		(stroke
			(width 0)
			(type default)
		)
	)
	(wire
		(pts
			(xy 203.2 62.23) (xy 214.63 62.23)
		)
		(stroke
			(width 0)
			(type default)
		)
	)
	(wire
		(pts
			(xy 328.93 78.74) (xy 347.98 78.74)
		)
		(stroke
			(width 0)
			(type default)
		)
	)
	(wire
		(pts
			(xy 264.16 92.71) (xy 250.19 92.71)
		)
		(stroke
			(width 0)
			(type default)
		)
	)
	(wire
		(pts
			(xy 196.85 204.47) (xy 209.55 204.47)
		)
		(stroke
			(width 0)
			(type default)
		)
	)
	(wire
		(pts
			(xy 264.16 80.01) (xy 250.19 80.01)
		)
		(stroke
			(width 0)
			(type default)
		)
	)
	(wire
		(pts
			(xy 92.71 204.47) (xy 110.49 204.47)
		)
		(stroke
			(width 0)
			(type default)
		)
	)
	(wire
		(pts
			(xy 196.85 231.14) (xy 209.55 231.14)
		)
		(stroke
			(width 0)
			(type default)
		)
	)
	(wire
		(pts
			(xy 328.93 111.76) (xy 328.93 114.3)
		)
		(stroke
			(width 0)
			(type default)
		)
	)
	(wire
		(pts
			(xy 110.49 93.98) (xy 92.71 93.98)
		)
		(stroke
			(width 0)
			(type default)
		)
	)
	(wire
		(pts
			(xy 264.16 87.63) (xy 250.19 87.63)
		)
		(stroke
			(width 0)
			(type default)
		)
	)
	(wire
		(pts
			(xy 203.2 54.61) (xy 214.63 54.61)
		)
		(stroke
			(width 0)
			(type default)
		)
	)
	(wire
		(pts
			(xy 190.5 86.36) (xy 190.5 88.9)
		)
		(stroke
			(width 0)
			(type default)
		)
	)
	(wire
		(pts
			(xy 92.71 40.64) (xy 95.25 40.64)
		)
		(stroke
			(width 0)
			(type default)
		)
	)
	(wire
		(pts
			(xy 177.8 88.9) (xy 190.5 88.9)
		)
		(stroke
			(width 0)
			(type default)
		)
	)
	(wire
		(pts
			(xy 295.91 62.23) (xy 295.91 63.5)
		)
		(stroke
			(width 0)
			(type default)
		)
	)
	(wire
		(pts
			(xy 307.34 54.61) (xy 295.91 54.61)
		)
		(stroke
			(width 0)
			(type default)
		)
	)
	(wire
		(pts
			(xy 110.49 73.66) (xy 92.71 73.66)
		)
		(stroke
			(width 0)
			(type default)
		)
	)
	(wire
		(pts
			(xy 95.25 158.75) (xy 95.25 153.67)
		)
		(stroke
			(width 0)
			(type default)
		)
	)
	(wire
		(pts
			(xy 273.05 212.09) (xy 273.05 209.55)
		)
		(stroke
			(width 0)
			(type default)
		)
	)
	(wire
		(pts
			(xy 95.25 35.56) (xy 92.71 35.56)
		)
		(stroke
			(width 0)
			(type default)
		)
	)
	(wire
		(pts
			(xy 203.2 64.77) (xy 214.63 64.77)
		)
		(stroke
			(width 0)
			(type default)
		)
	)
	(wire
		(pts
			(xy 262.89 255.27) (xy 273.05 255.27)
		)
		(stroke
			(width 0)
			(type default)
		)
	)
	(wire
		(pts
			(xy 110.49 104.14) (xy 92.71 104.14)
		)
		(stroke
			(width 0)
			(type default)
		)
	)
	(wire
		(pts
			(xy 240.03 209.55) (xy 252.73 209.55)
		)
		(stroke
			(width 0)
			(type default)
		)
	)
	(wire
		(pts
			(xy 115.57 153.67) (xy 115.57 158.75)
		)
		(stroke
			(width 0)
			(type default)
		)
	)
	(wire
		(pts
			(xy 92.71 173.99) (xy 110.49 173.99)
		)
		(stroke
			(width 0)
			(type default)
		)
	)
	(wire
		(pts
			(xy 264.16 57.15) (xy 250.19 57.15)
		)
		(stroke
			(width 0)
			(type default)
		)
	)
	(wire
		(pts
			(xy 95.25 214.63) (xy 95.25 222.25)
		)
		(stroke
			(width 0)
			(type default)
		)
	)
	(wire
		(pts
			(xy 262.89 231.14) (xy 273.05 231.14)
		)
		(stroke
			(width 0)
			(type default)
		)
	)
	(wire
		(pts
			(xy 130.81 29.21) (xy 130.81 30.48)
		)
		(stroke
			(width 0)
			(type default)
		)
	)
	(wire
		(pts
			(xy 229.87 233.68) (xy 229.87 231.14)
		)
		(stroke
			(width 0)
			(type default)
		)
	)
	(wire
		(pts
			(xy 92.71 196.85) (xy 110.49 196.85)
		)
		(stroke
			(width 0)
			(type default)
		)
	)
	(wire
		(pts
			(xy 219.71 252.73) (xy 229.87 252.73)
		)
		(stroke
			(width 0)
			(type default)
		)
	)
	(wire
		(pts
			(xy 240.03 255.27) (xy 252.73 255.27)
		)
		(stroke
			(width 0)
			(type default)
		)
	)
	(wire
		(pts
			(xy 92.71 201.93) (xy 110.49 201.93)
		)
		(stroke
			(width 0)
			(type default)
		)
	)
	(wire
		(pts
			(xy 92.71 222.25) (xy 95.25 222.25)
		)
		(stroke
			(width 0)
			(type default)
		)
	)
	(wire
		(pts
			(xy 313.69 111.76) (xy 314.96 111.76)
		)
		(stroke
			(width 0)
			(type default)
		)
	)
	(wire
		(pts
			(xy 264.16 74.93) (xy 250.19 74.93)
		)
		(stroke
			(width 0)
			(type default)
		)
	)
	(wire
		(pts
			(xy 203.2 110.49) (xy 214.63 110.49)
		)
		(stroke
			(width 0)
			(type default)
		)
	)
	(wire
		(pts
			(xy 264.16 97.79) (xy 250.19 97.79)
		)
		(stroke
			(width 0)
			(type default)
		)
	)
	(wire
		(pts
			(xy 190.5 88.9) (xy 199.39 88.9)
		)
		(stroke
			(width 0)
			(type default)
		)
	)
	(wire
		(pts
			(xy 273.05 233.68) (xy 273.05 231.14)
		)
		(stroke
			(width 0)
			(type default)
		)
	)
	(wire
		(pts
			(xy 110.49 109.22) (xy 92.71 109.22)
		)
		(stroke
			(width 0)
			(type default)
		)
	)
	(wire
		(pts
			(xy 264.16 102.87) (xy 250.19 102.87)
		)
		(stroke
			(width 0)
			(type default)
		)
	)
	(wire
		(pts
			(xy 203.2 97.79) (xy 214.63 97.79)
		)
		(stroke
			(width 0)
			(type default)
		)
	)
	(wire
		(pts
			(xy 346.71 91.44) (xy 346.71 88.9)
		)
		(stroke
			(width 0)
			(type default)
		)
	)
	(wire
		(pts
			(xy 346.71 88.9) (xy 347.98 88.9)
		)
		(stroke
			(width 0)
			(type default)
		)
	)
	(wire
		(pts
			(xy 219.71 228.6) (xy 229.87 228.6)
		)
		(stroke
			(width 0)
			(type default)
		)
	)
	(wire
		(pts
			(xy 110.49 60.96) (xy 92.71 60.96)
		)
		(stroke
			(width 0)
			(type default)
		)
	)
	(wire
		(pts
			(xy 328.93 54.61) (xy 341.63 54.61)
		)
		(stroke
			(width 0)
			(type default)
		)
	)
	(wire
		(pts
			(xy 314.96 109.22) (xy 314.96 111.76)
		)
		(stroke
			(width 0)
			(type default)
		)
	)
	(wire
		(pts
			(xy 240.03 207.01) (xy 252.73 207.01)
		)
		(stroke
			(width 0)
			(type default)
		)
	)
	(wire
		(pts
			(xy 240.03 212.09) (xy 252.73 212.09)
		)
		(stroke
			(width 0)
			(type default)
		)
	)
	(label "DDR3_A3"
		(at 110.49 224.79 180)
		(effects
			(font
				(size 1.27 1.27)
			)
			(justify right bottom)
		)
	)
	(label "DDR3_DQ14"
		(at 110.49 76.2 180)
		(effects
			(font
				(size 1.27 1.27)
			)
			(justify right bottom)
		)
	)
	(label "DDR3_LDQS_P"
		(at 110.49 171.45 180)
		(effects
			(font
				(size 1.27 1.27)
			)
			(justify right bottom)
		)
	)
	(label "DDR3_UDQS_P"
		(at 264.16 59.69 180)
		(effects
			(font
				(size 1.27 1.27)
			)
			(justify right bottom)
		)
	)
	(label "DDR3_LDQS_N"
		(at 264.16 57.15 180)
		(effects
			(font
				(size 1.27 1.27)
			)
			(justify right bottom)
		)
	)
	(label "DDR3_A10"
		(at 110.49 83.82 180)
		(effects
			(font
				(size 1.27 1.27)
			)
			(justify right bottom)
		)
	)
	(label "DDR3_A1"
		(at 196.85 255.27 0)
		(effects
			(font
				(size 1.27 1.27)
			)
			(justify left bottom)
		)
	)
	(label "DDR3_BA0"
		(at 203.2 128.27 0)
		(effects
			(font
				(size 1.27 1.27)
			)
			(justify left bottom)
		)
	)
	(label "DDR3_A2"
		(at 110.49 104.14 180)
		(effects
			(font
				(size 1.27 1.27)
			)
			(justify right bottom)
		)
	)
	(label "DDR3_BA1"
		(at 203.2 130.81 0)
		(effects
			(font
				(size 1.27 1.27)
			)
			(justify left bottom)
		)
	)
	(label "DDR3_A7"
		(at 196.85 228.6 0)
		(effects
			(font
				(size 1.27 1.27)
			)
			(justify left bottom)
		)
	)
	(label "DDR3_DQ0"
		(at 264.16 67.31 180)
		(effects
			(font
				(size 1.27 1.27)
			)
			(justify right bottom)
		)
	)
	(label "DDR3_CK_P"
		(at 110.49 217.17 180)
		(effects
			(font
				(size 1.27 1.27)
			)
			(justify right bottom)
		)
	)
	(label "DDR3_A6"
		(at 203.2 105.41 0)
		(effects
			(font
				(size 1.27 1.27)
			)
			(justify left bottom)
		)
	)
	(label "DDR3_BA2"
		(at 196.85 207.01 0)
		(effects
			(font
				(size 1.27 1.27)
			)
			(justify left bottom)
		)
	)
	(label "DDR3_A6"
		(at 240.03 209.55 0)
		(effects
			(font
				(size 1.27 1.27)
			)
			(justify left bottom)
		)
	)
	(label "~{DDR3_CAS}"
		(at 110.49 194.31 180)
		(effects
			(font
				(size 1.27 1.27)
			)
			(justify right bottom)
		)
	)
	(label "DDR3_DQ7"
		(at 110.49 181.61 180)
		(effects
			(font
				(size 1.27 1.27)
			)
			(justify right bottom)
		)
	)
	(label "DDR3_A10"
		(at 203.2 115.57 0)
		(effects
			(font
				(size 1.27 1.27)
			)
			(justify left bottom)
		)
	)
	(label "~{DDR3_CAS}"
		(at 240.03 250.19 0)
		(effects
			(font
				(size 1.27 1.27)
			)
			(justify left bottom)
		)
	)
	(label "DDR3_DQ12"
		(at 110.49 60.96 180)
		(effects
			(font
				(size 1.27 1.27)
			)
			(justify right bottom)
		)
	)
	(label "DDR3_DQ10"
		(at 264.16 92.71 180)
		(effects
			(font
				(size 1.27 1.27)
			)
			(justify right bottom)
		)
	)
	(label "~{DDR3_RESET}"
		(at 196.85 231.14 0)
		(effects
			(font
				(size 1.27 1.27)
			)
			(justify left bottom)
		)
	)
	(label "DDR3_A12"
		(at 203.2 120.65 0)
		(effects
			(font
				(size 1.27 1.27)
			)
			(justify left bottom)
		)
	)
	(label "DDR3_DQ4"
		(at 110.49 163.83 180)
		(effects
			(font
				(size 1.27 1.27)
			)
			(justify right bottom)
		)
	)
	(label "DDR3_DQ10"
		(at 110.49 71.12 180)
		(effects
			(font
				(size 1.27 1.27)
			)
			(justify right bottom)
		)
	)
	(label "DDR3_ODT"
		(at 110.49 191.77 180)
		(effects
			(font
				(size 1.27 1.27)
			)
			(justify right bottom)
		)
	)
	(label "DDR3_A2"
		(at 203.2 95.25 0)
		(effects
			(font
				(size 1.27 1.27)
			)
			(justify left bottom)
		)
	)
	(label "DDR3_CKE"
		(at 110.49 81.28 180)
		(effects
			(font
				(size 1.27 1.27)
			)
			(justify right bottom)
		)
	)
	(label "DDR3_DQ0"
		(at 110.49 168.91 180)
		(effects
			(font
				(size 1.27 1.27)
			)
			(justify right bottom)
		)
	)
	(label "DDR3_DQ4"
		(at 264.16 77.47 180)
		(effects
			(font
				(size 1.27 1.27)
			)
			(justify right bottom)
		)
	)
	(label "DDR3_DQ5"
		(at 110.49 176.53 180)
		(effects
			(font
				(size 1.27 1.27)
			)
			(justify right bottom)
		)
	)
	(label "DDR3_BA1"
		(at 196.85 252.73 0)
		(effects
			(font
				(size 1.27 1.27)
			)
			(justify left bottom)
		)
	)
	(label "DDR3_A12"
		(at 110.49 96.52 180)
		(effects
			(font
				(size 1.27 1.27)
			)
			(justify right bottom)
		)
	)
	(label "DDR3_LDQS_P"
		(at 264.16 54.61 180)
		(effects
			(font
				(size 1.27 1.27)
			)
			(justify right bottom)
		)
	)
	(label "DDR3_DQ8"
		(at 110.49 73.66 180)
		(effects
			(font
				(size 1.27 1.27)
			)
			(justify right bottom)
		)
	)
	(label "DDR3_A7"
		(at 203.2 107.95 0)
		(effects
			(font
				(size 1.27 1.27)
			)
			(justify left bottom)
		)
	)
	(label "DDR3_A10"
		(at 196.85 247.65 0)
		(effects
			(font
				(size 1.27 1.27)
			)
			(justify left bottom)
		)
	)
	(label "DDR3_DQ8"
		(at 264.16 87.63 180)
		(effects
			(font
				(size 1.27 1.27)
			)
			(justify right bottom)
		)
	)
	(label "DDR3_ODT"
		(at 240.03 247.65 0)
		(effects
			(font
				(size 1.27 1.27)
			)
			(justify left bottom)
		)
	)
	(label "DDR3_A11"
		(at 110.49 88.9 180)
		(effects
			(font
				(size 1.27 1.27)
			)
			(justify right bottom)
		)
	)
	(label "DDR3_A9"
		(at 203.2 113.03 0)
		(effects
			(font
				(size 1.27 1.27)
			)
			(justify left bottom)
		)
	)
	(label "DDR3_DQ11"
		(at 110.49 58.42 180)
		(effects
			(font
				(size 1.27 1.27)
			)
			(justify right bottom)
		)
	)
	(label "DDR3_DQ14"
		(at 264.16 102.87 180)
		(effects
			(font
				(size 1.27 1.27)
			)
			(justify right bottom)
		)
	)
	(label "DDR3_A8"
		(at 240.03 212.09 0)
		(effects
			(font
				(size 1.27 1.27)
			)
			(justify left bottom)
		)
	)
	(label "DDR3_DQ3"
		(at 264.16 74.93 180)
		(effects
			(font
				(size 1.27 1.27)
			)
			(justify right bottom)
		)
	)
	(label "DDR3_UDQS_N"
		(at 264.16 62.23 180)
		(effects
			(font
				(size 1.27 1.27)
			)
			(justify right bottom)
		)
	)
	(label "DDR3_CK_N"
		(at 110.49 219.71 180)
		(effects
			(font
				(size 1.27 1.27)
			)
			(justify right bottom)
		)
	)
	(label "DDR3_DQ15"
		(at 110.49 50.8 180)
		(effects
			(font
				(size 1.27 1.27)
			)
			(justify right bottom)
		)
	)
	(label "DDR3_A0"
		(at 203.2 88.9 0)
		(effects
			(font
				(size 1.27 1.27)
			)
			(justify left bottom)
		)
	)
	(label "DDR3_DQ1"
		(at 110.49 186.69 180)
		(effects
			(font
				(size 1.27 1.27)
			)
			(justify right bottom)
		)
	)
	(label "DDR3_DQ3"
		(at 110.49 184.15 180)
		(effects
			(font
				(size 1.27 1.27)
			)
			(justify right bottom)
		)
	)
	(label "DDR3_DQ12"
		(at 264.16 97.79 180)
		(effects
			(font
				(size 1.27 1.27)
			)
			(justify right bottom)
		)
	)
	(label "DDR3_A4"
		(at 203.2 100.33 0)
		(effects
			(font
				(size 1.27 1.27)
			)
			(justify left bottom)
		)
	)
	(label "~{DDR3_CS}"
		(at 196.85 209.55 0)
		(effects
			(font
				(size 1.27 1.27)
			)
			(justify left bottom)
		)
	)
	(label "~{DDR3_WE}"
		(at 196.85 212.09 0)
		(effects
			(font
				(size 1.27 1.27)
			)
			(justify left bottom)
		)
	)
	(label "DDR3_UDM"
		(at 203.2 74.93 0)
		(effects
			(font
				(size 1.27 1.27)
			)
			(justify left bottom)
		)
	)
	(label "~{DDR3_RESET}"
		(at 203.2 54.61 0)
		(effects
			(font
				(size 1.27 1.27)
			)
			(justify left bottom)
		)
	)
	(label "DDR3_LDM"
		(at 110.49 189.23 180)
		(effects
			(font
				(size 1.27 1.27)
			)
			(justify right bottom)
		)
	)
	(label "DDR3_A8"
		(at 110.49 111.76 180)
		(effects
			(font
				(size 1.27 1.27)
			)
			(justify right bottom)
		)
	)
	(label "DDR3_A3"
		(at 240.03 231.14 0)
		(effects
			(font
				(size 1.27 1.27)
			)
			(justify left bottom)
		)
	)
	(label "DDR3_A6"
		(at 110.49 109.22 180)
		(effects
			(font
				(size 1.27 1.27)
			)
			(justify right bottom)
		)
	)
	(label "DDR3_A9"
		(at 196.85 233.68 0)
		(effects
			(font
				(size 1.27 1.27)
			)
			(justify left bottom)
		)
	)
	(label "DDR3_DQ13"
		(at 264.16 100.33 180)
		(effects
			(font
				(size 1.27 1.27)
			)
			(justify right bottom)
		)
	)
	(label "DDR3_DQ7"
		(at 264.16 85.09 180)
		(effects
			(font
				(size 1.27 1.27)
			)
			(justify right bottom)
		)
	)
	(label "DDR3_ODT"
		(at 203.2 69.85 0)
		(effects
			(font
				(size 1.27 1.27)
			)
			(justify left bottom)
		)
	)
	(label "DDR3_DQ1"
		(at 264.16 69.85 180)
		(effects
			(font
				(size 1.27 1.27)
			)
			(justify right bottom)
		)
	)
	(label "DDR3_A13"
		(at 240.03 226.06 0)
		(effects
			(font
				(size 1.27 1.27)
			)
			(justify left bottom)
		)
	)
	(label "DDR3_DQ11"
		(at 264.16 95.25 180)
		(effects
			(font
				(size 1.27 1.27)
			)
			(justify right bottom)
		)
	)
	(label "DDR3_CKE"
		(at 240.03 255.27 0)
		(effects
			(font
				(size 1.27 1.27)
			)
			(justify left bottom)
		)
	)
	(label "DDR3_A13"
		(at 203.2 123.19 0)
		(effects
			(font
				(size 1.27 1.27)
			)
			(justify left bottom)
		)
	)
	(label "DDR3_CKE"
		(at 203.2 80.01 0)
		(effects
			(font
				(size 1.27 1.27)
			)
			(justify left bottom)
		)
	)
	(label "~{DDR3_CS}"
		(at 110.49 234.95 180)
		(effects
			(font
				(size 1.27 1.27)
			)
			(justify right bottom)
		)
	)
	(label "DDR3_A0"
		(at 240.03 233.68 0)
		(effects
			(font
				(size 1.27 1.27)
			)
			(justify left bottom)
		)
	)
	(label "DDR3_BA0"
		(at 196.85 204.47 0)
		(effects
			(font
				(size 1.27 1.27)
			)
			(justify left bottom)
		)
	)
	(label "DDR3_LDQS_N"
		(at 110.49 173.99 180)
		(effects
			(font
				(size 1.27 1.27)
			)
			(justify right bottom)
		)
	)
	(label "~{DDR3_RAS}"
		(at 203.2 57.15 0)
		(effects
			(font
				(size 1.27 1.27)
			)
			(justify left bottom)
		)
	)
	(label "DDR3_A13"
		(at 110.49 207.01 180)
		(effects
			(font
				(size 1.27 1.27)
			)
			(justify right bottom)
		)
	)
	(label "DDR3_A7"
		(at 110.49 106.68 180)
		(effects
			(font
				(size 1.27 1.27)
			)
			(justify right bottom)
		)
	)
	(label "DDR3_A1"
		(at 203.2 92.71 0)
		(effects
			(font
				(size 1.27 1.27)
			)
			(justify left bottom)
		)
	)
	(label "DDR3_A3"
		(at 203.2 97.79 0)
		(effects
			(font
				(size 1.27 1.27)
			)
			(justify left bottom)
		)
	)
	(label "DDR3_DQ9"
		(at 264.16 90.17 180)
		(effects
			(font
				(size 1.27 1.27)
			)
			(justify right bottom)
		)
	)
	(label "DDR3_A8"
		(at 203.2 110.49 0)
		(effects
			(font
				(size 1.27 1.27)
			)
			(justify left bottom)
		)
	)
	(label "DDR3_A12"
		(at 196.85 250.19 0)
		(effects
			(font
				(size 1.27 1.27)
			)
			(justify left bottom)
		)
	)
	(label "DDR3_DQ15"
		(at 264.16 105.41 180)
		(effects
			(font
				(size 1.27 1.27)
			)
			(justify right bottom)
		)
	)
	(label "~{DDR3_RAS}"
		(at 240.03 252.73 0)
		(effects
			(font
				(size 1.27 1.27)
			)
			(justify left bottom)
		)
	)
	(label "~{DDR3_CS}"
		(at 203.2 64.77 0)
		(effects
			(font
				(size 1.27 1.27)
			)
			(justify left bottom)
		)
	)
	(label "DDR3_BA0"
		(at 110.49 229.87 180)
		(effects
			(font
				(size 1.27 1.27)
			)
			(justify right bottom)
		)
	)
	(label "DDR3_A0"
		(at 110.49 199.39 180)
		(effects
			(font
				(size 1.27 1.27)
			)
			(justify right bottom)
		)
	)
	(label "~{DDR3_RESET}"
		(at 110.49 209.55 180)
		(effects
			(font
				(size 1.27 1.27)
			)
			(justify right bottom)
		)
	)
	(label "DDR3_LDM"
		(at 203.2 72.39 0)
		(effects
			(font
				(size 1.27 1.27)
			)
			(justify left bottom)
		)
	)
	(label "~{DDR3_WE}"
		(at 203.2 62.23 0)
		(effects
			(font
				(size 1.27 1.27)
			)
			(justify left bottom)
		)
	)
	(label "DDR3_BA2"
		(at 110.49 232.41 180)
		(effects
			(font
				(size 1.27 1.27)
			)
			(justify right bottom)
		)
	)
	(label "DDR3_DQ6"
		(at 264.16 82.55 180)
		(effects
			(font
				(size 1.27 1.27)
			)
			(justify right bottom)
		)
	)
	(label "DDR3_DQ2"
		(at 110.49 161.29 180)
		(effects
			(font
				(size 1.27 1.27)
			)
			(justify right bottom)
		)
	)
	(label "DDR3_UDM"
		(at 110.49 68.58 180)
		(effects
			(font
				(size 1.27 1.27)
			)
			(justify right bottom)
		)
	)
	(label "DDR3_A5"
		(at 110.49 204.47 180)
		(effects
			(font
				(size 1.27 1.27)
			)
			(justify right bottom)
		)
	)
	(label "DDR3_A1"
		(at 110.49 93.98 180)
		(effects
			(font
				(size 1.27 1.27)
			)
			(justify right bottom)
		)
	)
	(label "DDR3_UDQS_N"
		(at 110.49 55.88 180)
		(effects
			(font
				(size 1.27 1.27)
			)
			(justify right bottom)
		)
	)
	(label "DDR3_A11"
		(at 240.03 207.01 0)
		(effects
			(font
				(size 1.27 1.27)
			)
			(justify left bottom)
		)
	)
	(label "DDR3_BA2"
		(at 203.2 133.35 0)
		(effects
			(font
				(size 1.27 1.27)
			)
			(justify left bottom)
		)
	)
	(label "DDR3_DQ2"
		(at 264.16 72.39 180)
		(effects
			(font
				(size 1.27 1.27)
			)
			(justify right bottom)
		)
	)
	(label "~{DDR3_CAS}"
		(at 203.2 59.69 0)
		(effects
			(font
				(size 1.27 1.27)
			)
			(justify left bottom)
		)
	)
	(label "DDR3_A4"
		(at 110.49 114.3 180)
		(effects
			(font
				(size 1.27 1.27)
			)
			(justify right bottom)
		)
	)
	(label "DDR3_DQ6"
		(at 110.49 166.37 180)
		(effects
			(font
				(size 1.27 1.27)
			)
			(justify right bottom)
		)
	)
	(label "DDR3_DQ13"
		(at 110.49 45.72 180)
		(effects
			(font
				(size 1.27 1.27)
			)
			(justify right bottom)
		)
	)
	(label "DDR3_A11"
		(at 203.2 118.11 0)
		(effects
			(font
				(size 1.27 1.27)
			)
			(justify left bottom)
		)
	)
	(label "DDR3_A5"
		(at 203.2 102.87 0)
		(effects
			(font
				(size 1.27 1.27)
			)
			(justify left bottom)
		)
	)
	(label "DDR3_UDQS_P"
		(at 110.49 53.34 180)
		(effects
			(font
				(size 1.27 1.27)
			)
			(justify right bottom)
		)
	)
	(label "~{DDR3_WE}"
		(at 110.49 196.85 180)
		(effects
			(font
				(size 1.27 1.27)
			)
			(justify right bottom)
		)
	)
	(label "~{DDR3_RAS}"
		(at 110.49 99.06 180)
		(effects
			(font
				(size 1.27 1.27)
			)
			(justify right bottom)
		)
	)
	(label "DDR3_BA1"
		(at 110.49 86.36 180)
		(effects
			(font
				(size 1.27 1.27)
			)
			(justify right bottom)
		)
	)
	(label "DDR3_A5"
		(at 196.85 226.06 0)
		(effects
			(font
				(size 1.27 1.27)
			)
			(justify left bottom)
		)
	)
	(label "DDR3_CK_P"
		(at 177.8 78.74 0)
		(effects
			(font
				(size 1.27 1.27)
			)
			(justify left bottom)
		)
	)
	(label "DDR3_A2"
		(at 240.03 228.6 0)
		(effects
			(font
				(size 1.27 1.27)
			)
			(justify left bottom)
		)
	)
	(label "DDR3_A9"
		(at 110.49 201.93 180)
		(effects
			(font
				(size 1.27 1.27)
			)
			(justify right bottom)
		)
	)
	(label "DDR3_DQ9"
		(at 110.49 48.26 180)
		(effects
			(font
				(size 1.27 1.27)
			)
			(justify right bottom)
		)
	)
	(label "DDR3_DQ5"
		(at 264.16 80.01 180)
		(effects
			(font
				(size 1.27 1.27)
			)
			(justify right bottom)
		)
	)
	(label "DDR3_CK_N"
		(at 177.8 88.9 0)
		(effects
			(font
				(size 1.27 1.27)
			)
			(justify left bottom)
		)
	)
	(label "DDR3_A4"
		(at 240.03 204.47 0)
		(effects
			(font
				(size 1.27 1.27)
			)
			(justify left bottom)
		)
	)
	(global_label "Vtt"
		(shape input)
		(at 229.87 222.25 90)
		(fields_autoplaced yes)
		(effects
			(font
				(size 1.27 1.27)
			)
			(justify left)
		)
		(property "Intersheetrefs" "${INTERSHEET_REFS}"
			(at 229.7906 217.2969 90)
			(effects
				(font
					(size 1.27 1.27)
				)
				(justify left)
				(hide yes)
			)
		)
	)
	(global_label "Vtt"
		(shape input)
		(at 273.05 222.25 90)
		(fields_autoplaced yes)
		(effects
			(font
				(size 1.27 1.27)
			)
			(justify left)
		)
		(property "Intersheetrefs" "${INTERSHEET_REFS}"
			(at 272.9706 217.2969 90)
			(effects
				(font
					(size 1.27 1.27)
				)
				(justify left)
				(hide yes)
			)
		)
	)
	(global_label "Vtt"
		(shape input)
		(at 229.87 200.66 90)
		(fields_autoplaced yes)
		(effects
			(font
				(size 1.27 1.27)
			)
			(justify left)
		)
		(property "Intersheetrefs" "${INTERSHEET_REFS}"
			(at 229.7906 195.7069 90)
			(effects
				(font
					(size 1.27 1.27)
				)
				(justify left)
				(hide yes)
			)
		)
	)
	(global_label "Vtt"
		(shape input)
		(at 229.87 243.84 90)
		(fields_autoplaced yes)
		(effects
			(font
				(size 1.27 1.27)
			)
			(justify left)
		)
		(property "Intersheetrefs" "${INTERSHEET_REFS}"
			(at 229.7906 238.8869 90)
			(effects
				(font
					(size 1.27 1.27)
				)
				(justify left)
				(hide yes)
			)
		)
	)
	(global_label "Vref"
		(shape input)
		(at 148.59 152.4 90)
		(fields_autoplaced yes)
		(effects
			(font
				(size 1.27 1.27)
			)
			(justify left)
		)
		(property "Intersheetrefs" "${INTERSHEET_REFS}"
			(at 148.5106 146.2979 90)
			(effects
				(font
					(size 1.27 1.27)
				)
				(justify left)
				(hide yes)
			)
		)
	)
	(global_label "Vref"
		(shape input)
		(at 137.16 34.29 90)
		(fields_autoplaced yes)
		(effects
			(font
				(size 1.27 1.27)
			)
			(justify left)
		)
		(property "Intersheetrefs" "${INTERSHEET_REFS}"
			(at 137.0806 28.1879 90)
			(effects
				(font
					(size 1.27 1.27)
				)
				(justify left)
				(hide yes)
			)
		)
	)
	(global_label "Vref"
		(shape input)
		(at 308.61 107.95 90)
		(fields_autoplaced yes)
		(effects
			(font
				(size 1.27 1.27)
			)
			(justify left)
		)
		(property "Intersheetrefs" "${INTERSHEET_REFS}"
			(at 308.5306 101.8479 90)
			(effects
				(font
					(size 1.27 1.27)
				)
				(justify left)
				(hide yes)
			)
		)
	)
	(global_label "Vtt"
		(shape input)
		(at 273.05 200.66 90)
		(fields_autoplaced yes)
		(effects
			(font
				(size 1.27 1.27)
			)
			(justify left)
		)
		(property "Intersheetrefs" "${INTERSHEET_REFS}"
			(at 272.9706 195.7069 90)
			(effects
				(font
					(size 1.27 1.27)
				)
				(justify left)
				(hide yes)
			)
		)
	)
	(global_label "Vtt"
		(shape input)
		(at 273.05 243.84 90)
		(fields_autoplaced yes)
		(effects
			(font
				(size 1.27 1.27)
			)
			(justify left)
		)
		(property "Intersheetrefs" "${INTERSHEET_REFS}"
			(at 272.9706 238.8869 90)
			(effects
				(font
					(size 1.27 1.27)
				)
				(justify left)
				(hide yes)
			)
		)
	)
	(symbol
		(lib_id "antmicropower:GND")
		(at 120.65 48.26 0)
		(mirror y)
		(unit 1)
		(exclude_from_sim no)
		(in_bom yes)
		(on_board yes)
		(dnp no)
		(fields_autoplaced yes)
		(property "Reference" "#PWR086"
			(at 111.76 50.8 0)
			(effects
				(font
					(size 1.27 1.27)
					(thickness 0.15)
				)
				(justify left bottom)
				(hide yes)
			)
		)
		(property "Value" "GND"
			(at 118.11 49.5299 0)
			(effects
				(font
					(size 1.27 1.27)
					(thickness 0.15)
				)
				(justify left)
			)
		)
		(property "Footprint" ""
			(at 111.76 55.88 0)
			(effects
				(font
					(size 1.27 1.27)
					(thickness 0.15)
				)
				(justify left bottom)
				(hide yes)
			)
		)
		(property "Datasheet" ""
			(at 111.76 60.96 0)
			(effects
				(font
					(size 1.27 1.27)
					(thickness 0.15)
				)
				(justify left bottom)
				(hide yes)
			)
		)
		(property "Description" ""
			(at 120.65 48.26 0)
			(effects
				(font
					(size 1.27 1.27)
				)
				(hide yes)
			)
		)
		(property "Author" "Antmicro"
			(at 111.76 55.88 0)
			(effects
				(font
					(size 1.27 1.27)
					(thickness 0.15)
				)
				(justify left bottom)
				(hide yes)
			)
		)
		(property "License" "Apache-2.0"
			(at 111.76 58.42 0)
			(effects
				(font
					(size 1.27 1.27)
					(thickness 0.15)
				)
				(justify left bottom)
				(hide yes)
			)
		)
		(pin "1"
		)
		(instances
			(project "sdi-mipi-video-converter"
				(path ""
					(reference "#PWR086")
					(unit 1)
				)
			)
		)
	)
	(symbol
		(lib_id "antmicropower:GND")
		(at 307.34 63.5 0)
		(unit 1)
		(exclude_from_sim no)
		(in_bom yes)
		(on_board yes)
		(dnp no)
		(property "Reference" "#PWR096"
			(at 316.23 66.04 0)
			(effects
				(font
					(size 1.27 1.27)
					(thickness 0.15)
				)
				(justify left bottom)
				(hide yes)
			)
		)
		(property "Value" "GND"
			(at 309.245 68.58 0)
			(effects
				(font
					(size 1.27 1.27)
					(thickness 0.15)
				)
				(justify right)
			)
		)
		(property "Footprint" ""
			(at 316.23 71.12 0)
			(effects
				(font
					(size 1.27 1.27)
					(thickness 0.15)
				)
				(justify left bottom)
				(hide yes)
			)
		)
		(property "Datasheet" ""
			(at 316.23 76.2 0)
			(effects
				(font
					(size 1.27 1.27)
					(thickness 0.15)
				)
				(justify left bottom)
				(hide yes)
			)
		)
		(property "Description" ""
			(at 307.34 63.5 0)
			(effects
				(font
					(size 1.27 1.27)
				)
				(hide yes)
			)
		)
		(property "Author" "Antmicro"
			(at 316.23 71.12 0)
			(effects
				(font
					(size 1.27 1.27)
					(thickness 0.15)
				)
				(justify left bottom)
				(hide yes)
			)
		)
		(property "License" "Apache-2.0"
			(at 316.23 73.66 0)
			(effects
				(font
					(size 1.27 1.27)
					(thickness 0.15)
				)
				(justify left bottom)
				(hide yes)
			)
		)
		(pin "1"
		)
		(instances
			(project "sdi-mipi-video-converter"
				(path ""
					(reference "#PWR096")
					(unit 1)
				)
			)
		)
	)
	(symbol
		(lib_id "antmicroResistorNetworksArrays:R_4x51R_0402_array")
		(at 252.73 247.65 0)
		(unit 1)
		(exclude_from_sim no)
		(in_bom yes)
		(on_board yes)
		(dnp no)
		(fields_autoplaced yes)
		(property "Reference" "R50"
			(at 257.81 241.3 0)
			(effects
				(font
					(size 1.27 1.27)
					(thickness 0.15)
				)
			)
		)
		(property "Value" "R_4x51R_0402_array"
			(at 279.4 252.73 0)
			(effects
				(font
					(size 1.27 1.27)
					(thickness 0.15)
				)
				(justify left bottom)
				(hide yes)
			)
		)
		(property "Footprint" "antmicro-footprints:R_Array_4x0402"
			(at 279.4 257.81 0)
			(effects
				(font
					(size 1.27 1.27)
					(thickness 0.15)
				)
				(justify left bottom)
				(hide yes)
			)
		)
		(property "Datasheet" "http://industrial.panasonic.com/cdbs/www-data/pdf/AOC0000/AOC0000C14.pdf"
			(at 279.4 260.35 0)
			(effects
				(font
					(size 1.27 1.27)
					(thickness 0.15)
				)
				(justify left bottom)
				(hide yes)
			)
		)
		(property "Description" "Fixed Network Resistor, 51 ohm, Isolated, 4 Resistors, 0804 [2010 Metric], Convex, ± 5%"
			(at 252.73 247.65 0)
			(effects
				(font
					(size 1.27 1.27)
				)
				(hide yes)
			)
		)
		(property "MPN" "EXB28V510JX"
			(at 279.4 262.89 0)
			(effects
				(font
					(size 1.27 1.27)
					(thickness 0.15)
				)
				(justify left bottom)
				(hide yes)
			)
		)
		(property "Manufacturer" "Panasonic"
			(at 279.4 265.43 0)
			(effects
				(font
					(size 1.27 1.27)
					(thickness 0.15)
				)
				(justify left bottom)
				(hide yes)
			)
		)
		(property "Author" "Antmicro"
			(at 279.4 267.97 0)
			(effects
				(font
					(size 1.27 1.27)
					(thickness 0.15)
				)
				(justify left bottom)
				(hide yes)
			)
		)
		(property "License" "Apache-2.0"
			(at 279.4 270.51 0)
			(effects
				(font
					(size 1.27 1.27)
					(thickness 0.15)
				)
				(justify left bottom)
				(hide yes)
			)
		)
		(property "Val" "R_4x51R_0402"
			(at 257.81 243.84 0)
			(effects
				(font
					(size 1.27 1.27)
				)
			)
		)
		(pin "1"
		)
		(pin "2"
		)
		(pin "3"
		)
		(pin "4"
		)
		(pin "5"
		)
		(pin "6"
		)
		(pin "7"
		)
		(pin "8"
		)
		(instances
			(project "sdi-mipi-video-converter"
				(path ""
					(reference "R50")
					(unit 1)
				)
			)
		)
	)
	(symbol
		(lib_id "antmicropower:+1V5")
		(at 125.73 152.4 0)
		(unit 1)
		(exclude_from_sim no)
		(in_bom yes)
		(on_board yes)
		(dnp no)
		(fields_autoplaced yes)
		(property "Reference" "#PWR0229"
			(at 125.73 156.21 0)
			(effects
				(font
					(size 1.27 1.27)
				)
				(hide yes)
			)
		)
		(property "Value" "+1V5"
			(at 125.73 147.32 0)
			(effects
				(font
					(size 1.27 1.27)
				)
			)
		)
		(property "Footprint" ""
			(at 125.73 152.4 0)
			(effects
				(font
					(size 1.27 1.27)
				)
				(hide yes)
			)
		)
		(property "Datasheet" ""
			(at 125.73 152.4 0)
			(effects
				(font
					(size 1.27 1.27)
				)
				(hide yes)
			)
		)
		(property "Description" ""
			(at 125.73 152.4 0)
			(effects
				(font
					(size 1.27 1.27)
				)
				(hide yes)
			)
		)
		(pin "1"
		)
		(instances
			(project "sdi-mipi-video-converter"
				(path ""
					(reference "#PWR0229")
					(unit 1)
				)
			)
		)
	)
	(symbol
		(lib_id "antmicropower:GND")
		(at 295.91 63.5 0)
		(unit 1)
		(exclude_from_sim no)
		(in_bom yes)
		(on_board yes)
		(dnp no)
		(fields_autoplaced yes)
		(property "Reference" "#PWR093"
			(at 304.8 66.04 0)
			(effects
				(font
					(size 1.27 1.27)
					(thickness 0.15)
				)
				(justify left bottom)
				(hide yes)
			)
		)
		(property "Value" "GND"
			(at 295.91 68.58 0)
			(effects
				(font
					(size 1.27 1.27)
					(thickness 0.15)
				)
			)
		)
		(property "Footprint" ""
			(at 304.8 71.12 0)
			(effects
				(font
					(size 1.27 1.27)
					(thickness 0.15)
				)
				(justify left bottom)
				(hide yes)
			)
		)
		(property "Datasheet" ""
			(at 304.8 76.2 0)
			(effects
				(font
					(size 1.27 1.27)
					(thickness 0.15)
				)
				(justify left bottom)
				(hide yes)
			)
		)
		(property "Description" ""
			(at 295.91 63.5 0)
			(effects
				(font
					(size 1.27 1.27)
				)
				(hide yes)
			)
		)
		(property "Author" "Antmicro"
			(at 304.8 71.12 0)
			(effects
				(font
					(size 1.27 1.27)
					(thickness 0.15)
				)
				(justify left bottom)
				(hide yes)
			)
		)
		(property "License" "Apache-2.0"
			(at 304.8 73.66 0)
			(effects
				(font
					(size 1.27 1.27)
					(thickness 0.15)
				)
				(justify left bottom)
				(hide yes)
			)
		)
		(pin "1"
		)
		(instances
			(project "sdi-mipi-video-converter"
				(path ""
					(reference "#PWR093")
					(unit 1)
				)
			)
		)
	)
	(symbol
		(lib_id "antmicropower:GND")
		(at 313.69 120.65 0)
		(unit 1)
		(exclude_from_sim no)
		(in_bom yes)
		(on_board yes)
		(dnp no)
		(fields_autoplaced yes)
		(property "Reference" "#PWR0262"
			(at 322.58 123.19 0)
			(effects
				(font
					(size 1.27 1.27)
					(thickness 0.15)
				)
				(justify left bottom)
				(hide yes)
			)
		)
		(property "Value" "GND"
			(at 313.69 125.73 0)
			(effects
				(font
					(size 1.27 1.27)
					(thickness 0.15)
				)
			)
		)
		(property "Footprint" ""
			(at 322.58 128.27 0)
			(effects
				(font
					(size 1.27 1.27)
					(thickness 0.15)
				)
				(justify left bottom)
				(hide yes)
			)
		)
		(property "Datasheet" ""
			(at 322.58 133.35 0)
			(effects
				(font
					(size 1.27 1.27)
					(thickness 0.15)
				)
				(justify left bottom)
				(hide yes)
			)
		)
		(property "Description" ""
			(at 313.69 120.65 0)
			(effects
				(font
					(size 1.27 1.27)
				)
				(hide yes)
			)
		)
		(property "Author" "Antmicro"
			(at 322.58 128.27 0)
			(effects
				(font
					(size 1.27 1.27)
					(thickness 0.15)
				)
				(justify left bottom)
				(hide yes)
			)
		)
		(property "License" "Apache-2.0"
			(at 322.58 130.81 0)
			(effects
				(font
					(size 1.27 1.27)
					(thickness 0.15)
				)
				(justify left bottom)
				(hide yes)
			)
		)
		(pin "1"
		)
		(instances
			(project "sdi-mipi-video-converter"
				(path ""
					(reference "#PWR0262")
					(unit 1)
				)
			)
		)
	)
	(symbol
		(lib_id "antmicroResistorNetworksArrays:R_4x51R_0402_array")
		(at 209.55 247.65 0)
		(unit 1)
		(exclude_from_sim no)
		(in_bom yes)
		(on_board yes)
		(dnp no)
		(fields_autoplaced yes)
		(property "Reference" "R46"
			(at 214.63 241.3 0)
			(effects
				(font
					(size 1.27 1.27)
					(thickness 0.15)
				)
			)
		)
		(property "Value" "R_4x51R_0402_array"
			(at 236.22 252.73 0)
			(effects
				(font
					(size 1.27 1.27)
					(thickness 0.15)
				)
				(justify left bottom)
				(hide yes)
			)
		)
		(property "Footprint" "antmicro-footprints:R_Array_4x0402"
			(at 236.22 257.81 0)
			(effects
				(font
					(size 1.27 1.27)
					(thickness 0.15)
				)
				(justify left bottom)
				(hide yes)
			)
		)
		(property "Datasheet" "http://industrial.panasonic.com/cdbs/www-data/pdf/AOC0000/AOC0000C14.pdf"
			(at 236.22 260.35 0)
			(effects
				(font
					(size 1.27 1.27)
					(thickness 0.15)
				)
				(justify left bottom)
				(hide yes)
			)
		)
		(property "Description" "Fixed Network Resistor, 51 ohm, Isolated, 4 Resistors, 0804 [2010 Metric], Convex, ± 5%"
			(at 209.55 247.65 0)
			(effects
				(font
					(size 1.27 1.27)
				)
				(hide yes)
			)
		)
		(property "MPN" "EXB28V510JX"
			(at 236.22 262.89 0)
			(effects
				(font
					(size 1.27 1.27)
					(thickness 0.15)
				)
				(justify left bottom)
				(hide yes)
			)
		)
		(property "Manufacturer" "Panasonic"
			(at 236.22 265.43 0)
			(effects
				(font
					(size 1.27 1.27)
					(thickness 0.15)
				)
				(justify left bottom)
				(hide yes)
			)
		)
		(property "Author" "Antmicro"
			(at 236.22 267.97 0)
			(effects
				(font
					(size 1.27 1.27)
					(thickness 0.15)
				)
				(justify left bottom)
				(hide yes)
			)
		)
		(property "License" "Apache-2.0"
			(at 236.22 270.51 0)
			(effects
				(font
					(size 1.27 1.27)
					(thickness 0.15)
				)
				(justify left bottom)
				(hide yes)
			)
		)
		(property "Val" "R_4x51R_0402"
			(at 214.63 243.84 0)
			(effects
				(font
					(size 1.27 1.27)
				)
			)
		)
		(pin "1"
		)
		(pin "2"
		)
		(pin "3"
		)
		(pin "4"
		)
		(pin "5"
		)
		(pin "6"
		)
		(pin "7"
		)
		(pin "8"
		)
		(instances
			(project "sdi-mipi-video-converter"
				(path ""
					(reference "R46")
					(unit 1)
				)
			)
		)
	)
	(symbol
		(lib_id "antmicroResistorNetworksArrays:R_4x51R_0402_array")
		(at 209.55 226.06 0)
		(unit 1)
		(exclude_from_sim no)
		(in_bom yes)
		(on_board yes)
		(dnp no)
		(fields_autoplaced yes)
		(property "Reference" "R45"
			(at 214.63 219.71 0)
			(effects
				(font
					(size 1.27 1.27)
					(thickness 0.15)
				)
			)
		)
		(property "Value" "R_4x51R_0402_array"
			(at 236.22 231.14 0)
			(effects
				(font
					(size 1.27 1.27)
					(thickness 0.15)
				)
				(justify left bottom)
				(hide yes)
			)
		)
		(property "Footprint" "antmicro-footprints:R_Array_4x0402"
			(at 236.22 236.22 0)
			(effects
				(font
					(size 1.27 1.27)
					(thickness 0.15)
				)
				(justify left bottom)
				(hide yes)
			)
		)
		(property "Datasheet" "http://industrial.panasonic.com/cdbs/www-data/pdf/AOC0000/AOC0000C14.pdf"
			(at 236.22 238.76 0)
			(effects
				(font
					(size 1.27 1.27)
					(thickness 0.15)
				)
				(justify left bottom)
				(hide yes)
			)
		)
		(property "Description" "Fixed Network Resistor, 51 ohm, Isolated, 4 Resistors, 0804 [2010 Metric], Convex, ± 5%"
			(at 209.55 226.06 0)
			(effects
				(font
					(size 1.27 1.27)
				)
				(hide yes)
			)
		)
		(property "MPN" "EXB28V510JX"
			(at 236.22 241.3 0)
			(effects
				(font
					(size 1.27 1.27)
					(thickness 0.15)
				)
				(justify left bottom)
				(hide yes)
			)
		)
		(property "Manufacturer" "Panasonic"
			(at 236.22 243.84 0)
			(effects
				(font
					(size 1.27 1.27)
					(thickness 0.15)
				)
				(justify left bottom)
				(hide yes)
			)
		)
		(property "Author" "Antmicro"
			(at 236.22 246.38 0)
			(effects
				(font
					(size 1.27 1.27)
					(thickness 0.15)
				)
				(justify left bottom)
				(hide yes)
			)
		)
		(property "License" "Apache-2.0"
			(at 236.22 248.92 0)
			(effects
				(font
					(size 1.27 1.27)
					(thickness 0.15)
				)
				(justify left bottom)
				(hide yes)
			)
		)
		(property "Val" "R_4x51R_0402"
			(at 214.63 222.25 0)
			(effects
				(font
					(size 1.27 1.27)
				)
			)
		)
		(pin "1"
		)
		(pin "2"
		)
		(pin "3"
		)
		(pin "4"
		)
		(pin "5"
		)
		(pin "6"
		)
		(pin "7"
		)
		(pin "8"
		)
		(instances
			(project "sdi-mipi-video-converter"
				(path ""
					(reference "R45")
					(unit 1)
				)
			)
		)
	)
	(symbol
		(lib_id "antmicropower:GND")
		(at 328.93 87.63 0)
		(unit 1)
		(exclude_from_sim no)
		(in_bom yes)
		(on_board yes)
		(dnp no)
		(property "Reference" "#PWR0101"
			(at 337.82 90.17 0)
			(effects
				(font
					(size 1.27 1.27)
					(thickness 0.15)
				)
				(justify left bottom)
				(hide yes)
			)
		)
		(property "Value" "GND"
			(at 330.835 92.71 0)
			(effects
				(font
					(size 1.27 1.27)
					(thickness 0.15)
				)
				(justify right)
			)
		)
		(property "Footprint" ""
			(at 337.82 95.25 0)
			(effects
				(font
					(size 1.27 1.27)
					(thickness 0.15)
				)
				(justify left bottom)
				(hide yes)
			)
		)
		(property "Datasheet" ""
			(at 337.82 100.33 0)
			(effects
				(font
					(size 1.27 1.27)
					(thickness 0.15)
				)
				(justify left bottom)
				(hide yes)
			)
		)
		(property "Description" ""
			(at 328.93 87.63 0)
			(effects
				(font
					(size 1.27 1.27)
				)
				(hide yes)
			)
		)
		(property "Author" "Antmicro"
			(at 337.82 95.25 0)
			(effects
				(font
					(size 1.27 1.27)
					(thickness 0.15)
				)
				(justify left bottom)
				(hide yes)
			)
		)
		(property "License" "Apache-2.0"
			(at 337.82 97.79 0)
			(effects
				(font
					(size 1.27 1.27)
					(thickness 0.15)
				)
				(justify left bottom)
				(hide yes)
			)
		)
		(pin "1"
		)
		(instances
			(project "sdi-mipi-video-converter"
				(path ""
					(reference "#PWR0101")
					(unit 1)
				)
			)
		)
	)
	(symbol
		(lib_id "antmicroFPGAChips:CrossLink_LIFCL-40-9BG256C")
		(at 92.71 153.67 0)
		(mirror y)
		(unit 5)
		(exclude_from_sim no)
		(in_bom yes)
		(on_board yes)
		(dnp no)
		(fields_autoplaced yes)
		(property "Reference" "U11"
			(at 69.85 146.05 0)
			(effects
				(font
					(size 1.27 1.27)
					(thickness 0.15)
				)
			)
		)
		(property "Value" "LIFCL-40-9BG256C"
			(at 69.85 146.05 0)
			(effects
				(font
					(size 1.27 1.27)
					(thickness 0.15)
				)
				(hide yes)
			)
		)
		(property "Footprint" "antmicro-footprints:BGA-256_14x14mm_Layout16x16_P0.8mm"
			(at 39.37 161.29 0)
			(effects
				(font
					(size 1.27 1.27)
					(thickness 0.15)
				)
				(justify left bottom)
				(hide yes)
			)
		)
		(property "Datasheet" "https://www.latticesemi.com/-/media/LatticeSemi/Documents/DataSheets/CrossLink/FPGA-DS-02007-2-1-CrossLink-Family-Data-Sheet.ashx?document_id=51662"
			(at 39.37 163.83 0)
			(effects
				(font
					(size 1.27 1.27)
					(thickness 0.15)
				)
				(justify left bottom)
				(hide yes)
			)
		)
		(property "Description" "CrossLink-NX™ Field Programmable Gate Array 256-LFBGA"
			(at 92.71 153.67 0)
			(effects
				(font
					(size 1.27 1.27)
				)
				(hide yes)
			)
		)
		(property "MPN" "LIFCL-40-9BG256C"
			(at 69.85 148.59 0)
			(effects
				(font
					(size 1.27 1.27)
					(thickness 0.15)
				)
			)
		)
		(property "Manufacturer" "Lattice Semiconductor"
			(at 39.37 166.37 0)
			(effects
				(font
					(size 1.27 1.27)
					(thickness 0.15)
				)
				(justify left bottom)
				(hide yes)
			)
		)
		(property "Author" "Antmicro"
			(at 39.37 168.91 0)
			(effects
				(font
					(size 1.27 1.27)
					(thickness 0.15)
				)
				(justify left bottom)
				(hide yes)
			)
		)
		(property "License" "Apache-2.0"
			(at 39.37 171.45 0)
			(effects
				(font
					(size 1.27 1.27)
					(thickness 0.15)
				)
				(justify left bottom)
				(hide yes)
			)
		)
		(pin "B16"
		)
		(pin "C12"
		)
		(pin "C13"
		)
		(pin "C14"
		)
		(pin "C15"
		)
		(pin "C16"
		)
		(pin "D11"
		)
		(pin "D12"
		)
		(pin "D13"
		)
		(pin "D15"
		)
		(pin "D16"
		)
		(pin "E15"
		)
		(pin "E16"
		)
		(pin "D10"
		)
		(pin "E10"
		)
		(pin "E11"
		)
		(pin "E12"
		)
		(pin "E13"
		)
		(pin "E14"
		)
		(pin "E9"
		)
		(pin "F10"
		)
		(pin "F11"
		)
		(pin "F13"
		)
		(pin "F14"
		)
		(pin "F15"
		)
		(pin "F16"
		)
		(pin "F9"
		)
		(pin "G10"
		)
		(pin "G11"
		)
		(pin "G12"
		)
		(pin "G13"
		)
		(pin "G14"
		)
		(pin "G15"
		)
		(pin "G16"
		)
		(pin "G9"
		)
		(pin "H10"
		)
		(pin "H11"
		)
		(pin "H12"
		)
		(pin "H13"
		)
		(pin "H14"
		)
		(pin "H15"
		)
		(pin "H16"
		)
		(pin "J11"
		)
		(pin "J12"
		)
		(pin "J13"
		)
		(pin "J15"
		)
		(pin "J16"
		)
		(pin "K11"
		)
		(pin "K12"
		)
		(pin "L10"
		)
		(pin "L11"
		)
		(pin "L12"
		)
		(pin "M11"
		)
		(pin "M12"
		)
		(pin "M13"
		)
		(pin "M14"
		)
		(pin "M15"
		)
		(pin "M16"
		)
		(pin "N11"
		)
		(pin "N12"
		)
		(pin "N13"
		)
		(pin "N14"
		)
		(pin "N15"
		)
		(pin "N16"
		)
		(pin "P10"
		)
		(pin "P11"
		)
		(pin "P12"
		)
		(pin "P14"
		)
		(pin "P15"
		)
		(pin "P16"
		)
		(pin "R10"
		)
		(pin "R11"
		)
		(pin "R12"
		)
		(pin "R13"
		)
		(pin "R14"
		)
		(pin "R15"
		)
		(pin "R16"
		)
		(pin "T11"
		)
		(pin "T12"
		)
		(pin "T13"
		)
		(pin "T14"
		)
		(pin "T15"
		)
		(pin "L8"
		)
		(pin "L9"
		)
		(pin "M10"
		)
		(pin "M8"
		)
		(pin "M9"
		)
		(pin "N10"
		)
		(pin "N6"
		)
		(pin "N8"
		)
		(pin "N9"
		)
		(pin "P4"
		)
		(pin "P5"
		)
		(pin "P6"
		)
		(pin "P7"
		)
		(pin "P8"
		)
		(pin "P9"
		)
		(pin "R1"
		)
		(pin "R2"
		)
		(pin "R3"
		)
		(pin "R4"
		)
		(pin "R5"
		)
		(pin "R6"
		)
		(pin "R7"
		)
		(pin "R8"
		)
		(pin "R9"
		)
		(pin "T10"
		)
		(pin "T2"
		)
		(pin "T3"
		)
		(pin "T4"
		)
		(pin "T5"
		)
		(pin "T6"
		)
		(pin "T7"
		)
		(pin "T8"
		)
		(pin "T9"
		)
		(pin "K7"
		)
		(pin "L6"
		)
		(pin "L7"
		)
		(pin "M4"
		)
		(pin "M7"
		)
		(pin "N3"
		)
		(pin "N4"
		)
		(pin "N5"
		)
		(pin "P1"
		)
		(pin "P2"
		)
		(pin "P3"
		)
		(pin "H1"
		)
		(pin "H2"
		)
		(pin "H3"
		)
		(pin "H4"
		)
		(pin "H5"
		)
		(pin "H6"
		)
		(pin "J1"
		)
		(pin "J2"
		)
		(pin "J4"
		)
		(pin "J5"
		)
		(pin "J6"
		)
		(pin "K1"
		)
		(pin "K2"
		)
		(pin "K3"
		)
		(pin "K4"
		)
		(pin "K5"
		)
		(pin "K6"
		)
		(pin "L1"
		)
		(pin "L2"
		)
		(pin "L3"
		)
		(pin "L4"
		)
		(pin "L5"
		)
		(pin "M1"
		)
		(pin "M2"
		)
		(pin "M3"
		)
		(pin "N1"
		)
		(pin "N2"
		)
		(pin "D4"
		)
		(pin "D5"
		)
		(pin "D6"
		)
		(pin "E4"
		)
		(pin "E5"
		)
		(pin "E6"
		)
		(pin "F4"
		)
		(pin "F5"
		)
		(pin "F6"
		)
		(pin "G3"
		)
		(pin "G4"
		)
		(pin "G6"
		)
		(pin "B1"
		)
		(pin "B2"
		)
		(pin "C1"
		)
		(pin "C2"
		)
		(pin "D1"
		)
		(pin "D2"
		)
		(pin "E1"
		)
		(pin "E2"
		)
		(pin "F1"
		)
		(pin "F2"
		)
		(pin "A3"
		)
		(pin "A4"
		)
		(pin "A5"
		)
		(pin "A6"
		)
		(pin "A7"
		)
		(pin "B3"
		)
		(pin "B4"
		)
		(pin "B5"
		)
		(pin "B6"
		)
		(pin "B7"
		)
		(pin "K13"
		)
		(pin "K14"
		)
		(pin "K15"
		)
		(pin "K16"
		)
		(pin "L13"
		)
		(pin "L14"
		)
		(pin "L15"
		)
		(pin "L16"
		)
		(pin "A11"
		)
		(pin "A12"
		)
		(pin "A14"
		)
		(pin "A15"
		)
		(pin "A9"
		)
		(pin "B12"
		)
		(pin "B9"
		)
		(pin "C11"
		)
		(pin "A1"
		)
		(pin "A10"
		)
		(pin "A13"
		)
		(pin "A16"
		)
		(pin "A2"
		)
		(pin "A8"
		)
		(pin "B10"
		)
		(pin "B11"
		)
		(pin "B13"
		)
		(pin "B14"
		)
		(pin "B15"
		)
		(pin "B8"
		)
		(pin "C10"
		)
		(pin "C3"
		)
		(pin "C4"
		)
		(pin "C5"
		)
		(pin "C6"
		)
		(pin "C7"
		)
		(pin "C8"
		)
		(pin "C9"
		)
		(pin "D14"
		)
		(pin "D3"
		)
		(pin "D7"
		)
		(pin "D8"
		)
		(pin "D9"
		)
		(pin "E3"
		)
		(pin "E7"
		)
		(pin "E8"
		)
		(pin "F12"
		)
		(pin "F3"
		)
		(pin "F7"
		)
		(pin "F8"
		)
		(pin "G1"
		)
		(pin "G2"
		)
		(pin "G5"
		)
		(pin "G7"
		)
		(pin "G8"
		)
		(pin "H7"
		)
		(pin "H8"
		)
		(pin "H9"
		)
		(pin "J10"
		)
		(pin "J14"
		)
		(pin "J3"
		)
		(pin "J7"
		)
		(pin "J8"
		)
		(pin "J9"
		)
		(pin "K10"
		)
		(pin "K8"
		)
		(pin "K9"
		)
		(pin "M5"
		)
		(pin "M6"
		)
		(pin "N7"
		)
		(pin "P13"
		)
		(pin "T1"
		)
		(pin "T16"
		)
		(instances
			(project "sdi-mipi-video-converter"
				(path ""
					(reference "U11")
					(unit 5)
				)
			)
		)
	)
	(symbol
		(lib_id "antmicropower:GND")
		(at 328.93 120.65 0)
		(unit 1)
		(exclude_from_sim no)
		(in_bom yes)
		(on_board yes)
		(dnp no)
		(fields_autoplaced yes)
		(property "Reference" "#PWR0103"
			(at 337.82 123.19 0)
			(effects
				(font
					(size 1.27 1.27)
					(thickness 0.15)
				)
				(justify left bottom)
				(hide yes)
			)
		)
		(property "Value" "GND"
			(at 328.93 125.73 0)
			(effects
				(font
					(size 1.27 1.27)
					(thickness 0.15)
				)
			)
		)
		(property "Footprint" ""
			(at 337.82 128.27 0)
			(effects
				(font
					(size 1.27 1.27)
					(thickness 0.15)
				)
				(justify left bottom)
				(hide yes)
			)
		)
		(property "Datasheet" ""
			(at 337.82 133.35 0)
			(effects
				(font
					(size 1.27 1.27)
					(thickness 0.15)
				)
				(justify left bottom)
				(hide yes)
			)
		)
		(property "Description" ""
			(at 328.93 120.65 0)
			(effects
				(font
					(size 1.27 1.27)
				)
				(hide yes)
			)
		)
		(property "Author" "Antmicro"
			(at 337.82 128.27 0)
			(effects
				(font
					(size 1.27 1.27)
					(thickness 0.15)
				)
				(justify left bottom)
				(hide yes)
			)
		)
		(property "License" "Apache-2.0"
			(at 337.82 130.81 0)
			(effects
				(font
					(size 1.27 1.27)
					(thickness 0.15)
				)
				(justify left bottom)
				(hide yes)
			)
		)
		(pin "1"
		)
		(instances
			(project "sdi-mipi-video-converter"
				(path ""
					(reference "#PWR0103")
					(unit 1)
				)
			)
		)
	)
	(symbol
		(lib_id "antmicroResistorNetworksArrays:R_4x51R_0402_array")
		(at 209.55 204.47 0)
		(unit 1)
		(exclude_from_sim no)
		(in_bom yes)
		(on_board yes)
		(dnp no)
		(fields_autoplaced yes)
		(property "Reference" "R44"
			(at 214.63 198.12 0)
			(effects
				(font
					(size 1.27 1.27)
					(thickness 0.15)
				)
			)
		)
		(property "Value" "R_4x51R_0402_array"
			(at 236.22 209.55 0)
			(effects
				(font
					(size 1.27 1.27)
					(thickness 0.15)
				)
				(justify left bottom)
				(hide yes)
			)
		)
		(property "Footprint" "antmicro-footprints:R_Array_4x0402"
			(at 236.22 214.63 0)
			(effects
				(font
					(size 1.27 1.27)
					(thickness 0.15)
				)
				(justify left bottom)
				(hide yes)
			)
		)
		(property "Datasheet" "http://industrial.panasonic.com/cdbs/www-data/pdf/AOC0000/AOC0000C14.pdf"
			(at 236.22 217.17 0)
			(effects
				(font
					(size 1.27 1.27)
					(thickness 0.15)
				)
				(justify left bottom)
				(hide yes)
			)
		)
		(property "Description" "Fixed Network Resistor, 51 ohm, Isolated, 4 Resistors, 0804 [2010 Metric], Convex, ± 5%"
			(at 209.55 204.47 0)
			(effects
				(font
					(size 1.27 1.27)
				)
				(hide yes)
			)
		)
		(property "MPN" "EXB28V510JX"
			(at 236.22 219.71 0)
			(effects
				(font
					(size 1.27 1.27)
					(thickness 0.15)
				)
				(justify left bottom)
				(hide yes)
			)
		)
		(property "Manufacturer" "Panasonic"
			(at 236.22 222.25 0)
			(effects
				(font
					(size 1.27 1.27)
					(thickness 0.15)
				)
				(justify left bottom)
				(hide yes)
			)
		)
		(property "Author" "Antmicro"
			(at 236.22 224.79 0)
			(effects
				(font
					(size 1.27 1.27)
					(thickness 0.15)
				)
				(justify left bottom)
				(hide yes)
			)
		)
		(property "License" "Apache-2.0"
			(at 236.22 227.33 0)
			(effects
				(font
					(size 1.27 1.27)
					(thickness 0.15)
				)
				(justify left bottom)
				(hide yes)
			)
		)
		(property "Val" "R_4x51R_0402"
			(at 214.63 200.66 0)
			(effects
				(font
					(size 1.27 1.27)
				)
			)
		)
		(pin "1"
		)
		(pin "2"
		)
		(pin "3"
		)
		(pin "4"
		)
		(pin "5"
		)
		(pin "6"
		)
		(pin "7"
		)
		(pin "8"
		)
		(instances
			(project "sdi-mipi-video-converter"
				(path ""
					(reference "R44")
					(unit 1)
				)
			)
		)
	)
	(symbol
		(lib_id "antmicroResistorsmisc:R_100R_0201")
		(at 190.5 86.36 90)
		(unit 1)
		(exclude_from_sim no)
		(in_bom yes)
		(on_board yes)
		(dnp no)
		(fields_autoplaced yes)
		(property "Reference" "R43"
			(at 193.04 82.5499 90)
			(effects
				(font
					(size 1.27 1.27)
					(thickness 0.15)
				)
				(justify right)
			)
		)
		(property "Value" "R_100R_0201"
			(at 203.2 66.04 0)
			(effects
				(font
					(size 1.27 1.27)
					(thickness 0.15)
				)
				(justify left bottom)
				(hide yes)
			)
		)
		(property "Footprint" "antmicro-footprints:R_0201"
			(at 205.74 66.04 0)
			(effects
				(font
					(size 1.27 1.27)
					(thickness 0.15)
				)
				(justify left bottom)
				(hide yes)
			)
		)
		(property "Datasheet" "https://www.bourns.com/docs/product-datasheets/cr-a-as.pdf"
			(at 208.28 66.04 0)
			(effects
				(font
					(size 1.27 1.27)
					(thickness 0.15)
				)
				(justify left bottom)
				(hide yes)
			)
		)
		(property "Description" "SMD Chip Resistor, 100 ohm, ± 1%, 50 mW, 0201 [0603 Metric], Thick Film, Sulfur Resistant"
			(at 190.5 86.36 0)
			(effects
				(font
					(size 1.27 1.27)
				)
				(hide yes)
			)
		)
		(property "Manufacturer" "Bourns"
			(at 213.36 66.04 0)
			(effects
				(font
					(size 1.27 1.27)
					(thickness 0.15)
				)
				(justify left bottom)
				(hide yes)
			)
		)
		(property "MPN" "CR0201AFW-1000GAS"
			(at 210.82 66.04 0)
			(effects
				(font
					(size 1.27 1.27)
					(thickness 0.15)
				)
				(justify left bottom)
				(hide yes)
			)
		)
		(property "Val" "100R"
			(at 193.04 85.0899 90)
			(effects
				(font
					(size 1.27 1.27)
					(thickness 0.15)
				)
				(justify right)
			)
		)
		(property "License" "Apache-2.0"
			(at 215.9 66.04 0)
			(effects
				(font
					(size 1.27 1.27)
					(thickness 0.15)
				)
				(justify left bottom)
				(hide yes)
			)
		)
		(property "Author" "Antmicro"
			(at 218.44 66.04 0)
			(effects
				(font
					(size 1.27 1.27)
					(thickness 0.15)
				)
				(justify left bottom)
				(hide yes)
			)
		)
		(property "Tolerance" "1%"
			(at 200.66 66.04 0)
			(effects
				(font
					(size 1.27 1.27)
				)
				(justify left bottom)
				(hide yes)
			)
		)
		(pin "1"
		)
		(pin "2"
		)
		(instances
			(project "sdi-mipi-video-converter"
				(path ""
					(reference "R43")
					(unit 1)
				)
			)
		)
	)
	(symbol
		(lib_id "antmicroCapacitorsmisc:C_100n_0201")
		(at 132.08 45.72 90)
		(unit 1)
		(exclude_from_sim no)
		(in_bom yes)
		(on_board yes)
		(dnp no)
		(fields_autoplaced yes)
		(property "Reference" "C39"
			(at 134.62 41.9035 90)
			(effects
				(font
					(size 1.27 1.27)
					(thickness 0.15)
				)
				(justify right)
			)
		)
		(property "Value" "C_100n_0201"
			(at 142.24 25.4 0)
			(effects
				(font
					(size 1.27 1.27)
					(thickness 0.15)
				)
				(justify left bottom)
				(hide yes)
			)
		)
		(property "Footprint" "antmicro-footprints:C_0201"
			(at 144.78 25.4 0)
			(effects
				(font
					(size 1.27 1.27)
					(thickness 0.15)
				)
				(justify left bottom)
				(hide yes)
			)
		)
		(property "Datasheet" "https://www.yageo.com/en/Chart/Download/pdf/CC0201KRX6S5BB104"
			(at 147.32 25.4 0)
			(effects
				(font
					(size 1.27 1.27)
					(thickness 0.15)
				)
				(justify left bottom)
				(hide yes)
			)
		)
		(property "Description" "SMD Multilayer Ceramic Capacitor, 0.1 µF, 6.3 V, 0201 [0603 Metric], ± 10%, X6S, CC Series"
			(at 132.08 45.72 0)
			(effects
				(font
					(size 1.27 1.27)
				)
				(hide yes)
			)
		)
		(property "Manufacturer" "YAGEO"
			(at 152.4 25.4 0)
			(effects
				(font
					(size 1.27 1.27)
					(thickness 0.15)
				)
				(justify left bottom)
				(hide yes)
			)
		)
		(property "MPN" "CC0201KRX6S5BB104"
			(at 149.86 25.4 0)
			(effects
				(font
					(size 1.27 1.27)
					(thickness 0.15)
				)
				(justify left bottom)
				(hide yes)
			)
		)
		(property "Val" "100n"
			(at 134.62 44.4435 90)
			(effects
				(font
					(size 1.27 1.27)
					(thickness 0.15)
				)
				(justify right)
			)
		)
		(property "License" "Apache-2.0"
			(at 154.94 25.4 0)
			(effects
				(font
					(size 1.27 1.27)
					(thickness 0.15)
				)
				(justify left bottom)
				(hide yes)
			)
		)
		(property "Author" "Antmicro"
			(at 157.48 25.4 0)
			(effects
				(font
					(size 1.27 1.27)
					(thickness 0.15)
				)
				(justify left bottom)
				(hide yes)
			)
		)
		(property "Voltage" ""
			(at 160.02 25.4 0)
			(effects
				(font
					(size 1.27 1.27)
				)
				(justify left bottom)
				(hide yes)
			)
		)
		(property "Dielectric" ""
			(at 162.56 25.4 0)
			(effects
				(font
					(size 1.27 1.27)
				)
				(justify left bottom)
				(hide yes)
			)
		)
		(property "Public" "False"
			(at 165.1 25.4 0)
			(effects
				(font
					(size 1.27 1.27)
				)
				(justify left bottom)
				(hide yes)
			)
		)
		(pin "1"
		)
		(pin "2"
		)
		(instances
			(project "sdi-mipi-video-converter"
				(path ""
					(reference "C39")
					(unit 1)
				)
			)
		)
	)
	(symbol
		(lib_id "antmicropower:GND")
		(at 295.91 87.63 0)
		(unit 1)
		(exclude_from_sim no)
		(in_bom yes)
		(on_board yes)
		(dnp no)
		(fields_autoplaced yes)
		(property "Reference" "#PWR095"
			(at 304.8 90.17 0)
			(effects
				(font
					(size 1.27 1.27)
					(thickness 0.15)
				)
				(justify left bottom)
				(hide yes)
			)
		)
		(property "Value" "GND"
			(at 295.91 92.71 0)
			(effects
				(font
					(size 1.27 1.27)
					(thickness 0.15)
				)
			)
		)
		(property "Footprint" ""
			(at 304.8 95.25 0)
			(effects
				(font
					(size 1.27 1.27)
					(thickness 0.15)
				)
				(justify left bottom)
				(hide yes)
			)
		)
		(property "Datasheet" ""
			(at 304.8 100.33 0)
			(effects
				(font
					(size 1.27 1.27)
					(thickness 0.15)
				)
				(justify left bottom)
				(hide yes)
			)
		)
		(property "Description" ""
			(at 295.91 87.63 0)
			(effects
				(font
					(size 1.27 1.27)
				)
				(hide yes)
			)
		)
		(property "Author" "Antmicro"
			(at 304.8 95.25 0)
			(effects
				(font
					(size 1.27 1.27)
					(thickness 0.15)
				)
				(justify left bottom)
				(hide yes)
			)
		)
		(property "License" "Apache-2.0"
			(at 304.8 97.79 0)
			(effects
				(font
					(size 1.27 1.27)
					(thickness 0.15)
				)
				(justify left bottom)
				(hide yes)
			)
		)
		(pin "1"
		)
		(instances
			(project "sdi-mipi-video-converter"
				(path ""
					(reference "#PWR095")
					(unit 1)
				)
			)
		)
	)
	(symbol
		(lib_id "antmicropower:+1V5")
		(at 314.96 102.87 0)
		(unit 1)
		(exclude_from_sim no)
		(in_bom yes)
		(on_board yes)
		(dnp no)
		(fields_autoplaced yes)
		(property "Reference" "#PWR0261"
			(at 314.96 106.68 0)
			(effects
				(font
					(size 1.27 1.27)
				)
				(hide yes)
			)
		)
		(property "Value" "+1V5"
			(at 314.96 97.79 0)
			(effects
				(font
					(size 1.27 1.27)
				)
			)
		)
		(property "Footprint" ""
			(at 314.96 102.87 0)
			(effects
				(font
					(size 1.27 1.27)
				)
				(hide yes)
			)
		)
		(property "Datasheet" ""
			(at 314.96 102.87 0)
			(effects
				(font
					(size 1.27 1.27)
				)
				(hide yes)
			)
		)
		(property "Description" ""
			(at 314.96 102.87 0)
			(effects
				(font
					(size 1.27 1.27)
				)
				(hide yes)
			)
		)
		(pin "1"
		)
		(instances
			(project "sdi-mipi-video-converter"
				(path ""
					(reference "#PWR0261")
					(unit 1)
				)
			)
		)
	)
	(symbol
		(lib_id "antmicroCapacitors0402:C_100n_0402")
		(at 295.91 62.23 270)
		(mirror x)
		(unit 1)
		(exclude_from_sim no)
		(in_bom yes)
		(on_board yes)
		(dnp no)
		(fields_autoplaced yes)
		(property "Reference" "C41"
			(at 298.45 58.4135 90)
			(effects
				(font
					(size 1.27 1.27)
					(thickness 0.15)
				)
				(justify left)
			)
		)
		(property "Value" "C_100n_0402"
			(at 285.75 41.91 0)
			(effects
				(font
					(size 1.27 1.27)
					(thickness 0.15)
				)
				(justify left bottom)
				(hide yes)
			)
		)
		(property "Footprint" "antmicro-footprints:C_0402_1005Metric"
			(at 283.21 41.91 0)
			(effects
				(font
					(size 1.27 1.27)
					(thickness 0.15)
				)
				(justify left bottom)
				(hide yes)
			)
		)
		(property "Datasheet" "https://www.murata.com/products/productdetail?partno=GRM155R61H104KE14%23"
			(at 280.67 41.91 0)
			(effects
				(font
					(size 1.27 1.27)
					(thickness 0.15)
				)
				(justify left bottom)
				(hide yes)
			)
		)
		(property "Description" "SMD Multilayer Ceramic Capacitor, 0.1 µF, 50 V, 0402 [1005 Metric], ± 10%, X5R, GRM Series"
			(at 295.91 62.23 0)
			(effects
				(font
					(size 1.27 1.27)
				)
				(hide yes)
			)
		)
		(property "Manufacturer" "Murata"
			(at 275.59 41.91 0)
			(effects
				(font
					(size 1.27 1.27)
					(thickness 0.15)
				)
				(justify left bottom)
				(hide yes)
			)
		)
		(property "MPN" "GRM155R61H104KE14D"
			(at 278.13 41.91 0)
			(effects
				(font
					(size 1.27 1.27)
					(thickness 0.15)
				)
				(justify left bottom)
				(hide yes)
			)
		)
		(property "Val" "100n"
			(at 298.45 60.9535 90)
			(effects
				(font
					(size 1.27 1.27)
					(thickness 0.15)
				)
				(justify left)
			)
		)
		(property "License" "Apache-2.0"
			(at 273.05 41.91 0)
			(effects
				(font
					(size 1.27 1.27)
					(thickness 0.15)
				)
				(justify left bottom)
				(hide yes)
			)
		)
		(property "Author" "Antmicro"
			(at 270.51 41.91 0)
			(effects
				(font
					(size 1.27 1.27)
					(thickness 0.15)
				)
				(justify left bottom)
				(hide yes)
			)
		)
		(property "Voltage" "50V"
			(at 267.97 41.91 0)
			(effects
				(font
					(size 1.27 1.27)
				)
				(justify left bottom)
				(hide yes)
			)
		)
		(property "Dielectric" "X5R"
			(at 265.43 41.91 0)
			(effects
				(font
					(size 1.27 1.27)
				)
				(justify left bottom)
				(hide yes)
			)
		)
		(pin "1"
		)
		(pin "2"
		)
		(instances
			(project "sdi-mipi-video-converter"
				(path ""
					(reference "C41")
					(unit 1)
				)
			)
		)
	)
	(symbol
		(lib_id "antmicroCapacitorsmisc:C_100n_0201")
		(at 138.43 163.83 90)
		(unit 1)
		(exclude_from_sim no)
		(in_bom yes)
		(on_board yes)
		(dnp no)
		(fields_autoplaced yes)
		(property "Reference" "C40"
			(at 140.97 160.0135 90)
			(effects
				(font
					(size 1.27 1.27)
					(thickness 0.15)
				)
				(justify right)
			)
		)
		(property "Value" "C_100n_0201"
			(at 148.59 143.51 0)
			(effects
				(font
					(size 1.27 1.27)
					(thickness 0.15)
				)
				(justify left bottom)
				(hide yes)
			)
		)
		(property "Footprint" "antmicro-footprints:C_0201"
			(at 151.13 143.51 0)
			(effects
				(font
					(size 1.27 1.27)
					(thickness 0.15)
				)
				(justify left bottom)
				(hide yes)
			)
		)
		(property "Datasheet" "https://www.yageo.com/en/Chart/Download/pdf/CC0201KRX6S5BB104"
			(at 153.67 143.51 0)
			(effects
				(font
					(size 1.27 1.27)
					(thickness 0.15)
				)
				(justify left bottom)
				(hide yes)
			)
		)
		(property "Description" "SMD Multilayer Ceramic Capacitor, 0.1 µF, 6.3 V, 0201 [0603 Metric], ± 10%, X6S, CC Series"
			(at 138.43 163.83 0)
			(effects
				(font
					(size 1.27 1.27)
				)
				(hide yes)
			)
		)
		(property "Manufacturer" "YAGEO"
			(at 158.75 143.51 0)
			(effects
				(font
					(size 1.27 1.27)
					(thickness 0.15)
				)
				(justify left bottom)
				(hide yes)
			)
		)
		(property "MPN" "CC0201KRX6S5BB104"
			(at 156.21 143.51 0)
			(effects
				(font
					(size 1.27 1.27)
					(thickness 0.15)
				)
				(justify left bottom)
				(hide yes)
			)
		)
		(property "Val" "100n"
			(at 140.97 162.5535 90)
			(effects
				(font
					(size 1.27 1.27)
					(thickness 0.15)
				)
				(justify right)
			)
		)
		(property "License" "Apache-2.0"
			(at 161.29 143.51 0)
			(effects
				(font
					(size 1.27 1.27)
					(thickness 0.15)
				)
				(justify left bottom)
				(hide yes)
			)
		)
		(property "Author" "Antmicro"
			(at 163.83 143.51 0)
			(effects
				(font
					(size 1.27 1.27)
					(thickness 0.15)
				)
				(justify left bottom)
				(hide yes)
			)
		)
		(property "Voltage" ""
			(at 166.37 143.51 0)
			(effects
				(font
					(size 1.27 1.27)
				)
				(justify left bottom)
				(hide yes)
			)
		)
		(property "Dielectric" ""
			(at 168.91 143.51 0)
			(effects
				(font
					(size 1.27 1.27)
				)
				(justify left bottom)
				(hide yes)
			)
		)
		(property "Public" "False"
			(at 171.45 143.51 0)
			(effects
				(font
					(size 1.27 1.27)
				)
				(justify left bottom)
				(hide yes)
			)
		)
		(pin "1"
		)
		(pin "2"
		)
		(instances
			(project "sdi-mipi-video-converter"
				(path ""
					(reference "C40")
					(unit 1)
				)
			)
		)
	)
	(symbol
		(lib_id "antmicroMemory:MT41K128M16JT-125_K")
		(at 214.63 54.61 0)
		(unit 1)
		(exclude_from_sim no)
		(in_bom yes)
		(on_board yes)
		(dnp no)
		(fields_autoplaced yes)
		(property "Reference" "U12"
			(at 232.41 46.99 0)
			(effects
				(font
					(size 1.27 1.27)
					(thickness 0.15)
				)
			)
		)
		(property "Value" "MT41K128M16JT-125_K"
			(at 232.41 49.53 0)
			(effects
				(font
					(size 1.27 1.27)
					(thickness 0.15)
				)
			)
		)
		(property "Footprint" "antmicro-footprints:BGA-96-48_8x14mm_Layout16x9_P0.8mm"
			(at 265.43 64.77 0)
			(effects
				(font
					(size 1.27 1.27)
					(thickness 0.15)
				)
				(justify left bottom)
				(hide yes)
			)
		)
		(property "Datasheet" "https://www.mouser.com/datasheet/2/671/mict_s_a0002296722_1-2290882.pdf"
			(at 265.43 67.31 0)
			(effects
				(font
					(size 1.27 1.27)
					(thickness 0.15)
				)
				(justify left bottom)
				(hide yes)
			)
		)
		(property "Description" "SDRAM - DDR3L Memory IC 2Gbit Parallel 800 MHz 13.75 ns 96-FBGA (8x14)"
			(at 214.63 54.61 0)
			(effects
				(font
					(size 1.27 1.27)
				)
				(hide yes)
			)
		)
		(property "Manufacturer" "Micron Technology"
			(at 265.43 69.85 0)
			(effects
				(font
					(size 1.27 1.27)
					(thickness 0.15)
				)
				(justify left bottom)
				(hide yes)
			)
		)
		(property "MPN" "MT41K128M16JT-125:K"
			(at 265.43 72.39 0)
			(effects
				(font
					(size 1.27 1.27)
					(thickness 0.15)
				)
				(justify left bottom)
				(hide yes)
			)
		)
		(property "Author" "Antmicro"
			(at 265.43 74.93 0)
			(effects
				(font
					(size 1.27 1.27)
					(thickness 0.15)
				)
				(justify left bottom)
				(hide yes)
			)
		)
		(property "License" "Apache-2.0"
			(at 265.43 77.47 0)
			(effects
				(font
					(size 1.27 1.27)
					(thickness 0.15)
				)
				(justify left bottom)
				(hide yes)
			)
		)
		(pin "A2"
		)
		(pin "A3"
		)
		(pin "A7"
		)
		(pin "B7"
		)
		(pin "B8"
		)
		(pin "C2"
		)
		(pin "C3"
		)
		(pin "C7"
		)
		(pin "C8"
		)
		(pin "D3"
		)
		(pin "D7"
		)
		(pin "E3"
		)
		(pin "E7"
		)
		(pin "F2"
		)
		(pin "F3"
		)
		(pin "F7"
		)
		(pin "F8"
		)
		(pin "G2"
		)
		(pin "G3"
		)
		(pin "H3"
		)
		(pin "H7"
		)
		(pin "H8"
		)
		(pin "J1"
		)
		(pin "J3"
		)
		(pin "J7"
		)
		(pin "J9"
		)
		(pin "K1"
		)
		(pin "K3"
		)
		(pin "K7"
		)
		(pin "K9"
		)
		(pin "L1"
		)
		(pin "L2"
		)
		(pin "L3"
		)
		(pin "L7"
		)
		(pin "L8"
		)
		(pin "L9"
		)
		(pin "M2"
		)
		(pin "M3"
		)
		(pin "M7"
		)
		(pin "N2"
		)
		(pin "N3"
		)
		(pin "N7"
		)
		(pin "N8"
		)
		(pin "P2"
		)
		(pin "P3"
		)
		(pin "P7"
		)
		(pin "P8"
		)
		(pin "R2"
		)
		(pin "R3"
		)
		(pin "R7"
		)
		(pin "R8"
		)
		(pin "T2"
		)
		(pin "T3"
		)
		(pin "T7"
		)
		(pin "T8"
		)
		(pin "A1"
		)
		(pin "A8"
		)
		(pin "A9"
		)
		(pin "B1"
		)
		(pin "B2"
		)
		(pin "B3"
		)
		(pin "B9"
		)
		(pin "C1"
		)
		(pin "C9"
		)
		(pin "D1"
		)
		(pin "D2"
		)
		(pin "D8"
		)
		(pin "D9"
		)
		(pin "E1"
		)
		(pin "E2"
		)
		(pin "E8"
		)
		(pin "E9"
		)
		(pin "F1"
		)
		(pin "F9"
		)
		(pin "G1"
		)
		(pin "G7"
		)
		(pin "G8"
		)
		(pin "G9"
		)
		(pin "H1"
		)
		(pin "H2"
		)
		(pin "H9"
		)
		(pin "J2"
		)
		(pin "J8"
		)
		(pin "K2"
		)
		(pin "K8"
		)
		(pin "M1"
		)
		(pin "M8"
		)
		(pin "M9"
		)
		(pin "N1"
		)
		(pin "N9"
		)
		(pin "P1"
		)
		(pin "P9"
		)
		(pin "R1"
		)
		(pin "R9"
		)
		(pin "T1"
		)
		(pin "T9"
		)
		(instances
			(project "sdi-mipi-video-converter"
				(path ""
					(reference "U12")
					(unit 1)
				)
			)
		)
	)
	(symbol
		(lib_id "antmicropower:GND")
		(at 318.77 63.5 0)
		(unit 1)
		(exclude_from_sim no)
		(in_bom yes)
		(on_board yes)
		(dnp no)
		(fields_autoplaced yes)
		(property "Reference" "#PWR098"
			(at 327.66 66.04 0)
			(effects
				(font
					(size 1.27 1.27)
					(thickness 0.15)
				)
				(justify left bottom)
				(hide yes)
			)
		)
		(property "Value" "GND"
			(at 318.77 68.58 0)
			(effects
				(font
					(size 1.27 1.27)
					(thickness 0.15)
				)
			)
		)
		(property "Footprint" ""
			(at 327.66 71.12 0)
			(effects
				(font
					(size 1.27 1.27)
					(thickness 0.15)
				)
				(justify left bottom)
				(hide yes)
			)
		)
		(property "Datasheet" ""
			(at 327.66 76.2 0)
			(effects
				(font
					(size 1.27 1.27)
					(thickness 0.15)
				)
				(justify left bottom)
				(hide yes)
			)
		)
		(property "Description" ""
			(at 318.77 63.5 0)
			(effects
				(font
					(size 1.27 1.27)
				)
				(hide yes)
			)
		)
		(property "Author" "Antmicro"
			(at 327.66 71.12 0)
			(effects
				(font
					(size 1.27 1.27)
					(thickness 0.15)
				)
				(justify left bottom)
				(hide yes)
			)
		)
		(property "License" "Apache-2.0"
			(at 327.66 73.66 0)
			(effects
				(font
					(size 1.27 1.27)
					(thickness 0.15)
				)
				(justify left bottom)
				(hide yes)
			)
		)
		(pin "1"
		)
		(instances
			(project "sdi-mipi-video-converter"
				(path ""
					(reference "#PWR098")
					(unit 1)
				)
			)
		)
	)
	(symbol
		(lib_id "antmicroCapacitorsmisc:C_100n_0201")
		(at 130.81 35.56 270)
		(mirror x)
		(unit 1)
		(exclude_from_sim no)
		(in_bom yes)
		(on_board yes)
		(dnp no)
		(fields_autoplaced yes)
		(property "Reference" "C38"
			(at 128.27 31.7435 90)
			(effects
				(font
					(size 1.27 1.27)
					(thickness 0.15)
				)
				(justify right)
			)
		)
		(property "Value" "C_100n_0201"
			(at 120.65 15.24 0)
			(effects
				(font
					(size 1.27 1.27)
					(thickness 0.15)
				)
				(justify left bottom)
				(hide yes)
			)
		)
		(property "Footprint" "antmicro-footprints:C_0201"
			(at 118.11 15.24 0)
			(effects
				(font
					(size 1.27 1.27)
					(thickness 0.15)
				)
				(justify left bottom)
				(hide yes)
			)
		)
		(property "Datasheet" "https://www.yageo.com/en/Chart/Download/pdf/CC0201KRX6S5BB104"
			(at 115.57 15.24 0)
			(effects
				(font
					(size 1.27 1.27)
					(thickness 0.15)
				)
				(justify left bottom)
				(hide yes)
			)
		)
		(property "Description" "SMD Multilayer Ceramic Capacitor, 0.1 µF, 6.3 V, 0201 [0603 Metric], ± 10%, X6S, CC Series"
			(at 130.81 35.56 0)
			(effects
				(font
					(size 1.27 1.27)
				)
				(hide yes)
			)
		)
		(property "Manufacturer" "YAGEO"
			(at 110.49 15.24 0)
			(effects
				(font
					(size 1.27 1.27)
					(thickness 0.15)
				)
				(justify left bottom)
				(hide yes)
			)
		)
		(property "MPN" "CC0201KRX6S5BB104"
			(at 113.03 15.24 0)
			(effects
				(font
					(size 1.27 1.27)
					(thickness 0.15)
				)
				(justify left bottom)
				(hide yes)
			)
		)
		(property "Val" "100n"
			(at 128.27 34.2835 90)
			(effects
				(font
					(size 1.27 1.27)
					(thickness 0.15)
				)
				(justify right)
			)
		)
		(property "License" "Apache-2.0"
			(at 107.95 15.24 0)
			(effects
				(font
					(size 1.27 1.27)
					(thickness 0.15)
				)
				(justify left bottom)
				(hide yes)
			)
		)
		(property "Author" "Antmicro"
			(at 105.41 15.24 0)
			(effects
				(font
					(size 1.27 1.27)
					(thickness 0.15)
				)
				(justify left bottom)
				(hide yes)
			)
		)
		(property "Voltage" ""
			(at 102.87 15.24 0)
			(effects
				(font
					(size 1.27 1.27)
				)
				(justify left bottom)
				(hide yes)
			)
		)
		(property "Dielectric" ""
			(at 100.33 15.24 0)
			(effects
				(font
					(size 1.27 1.27)
				)
				(justify left bottom)
				(hide yes)
			)
		)
		(property "Public" "False"
			(at 97.79 15.24 0)
			(effects
				(font
					(size 1.27 1.27)
				)
				(justify left bottom)
				(hide yes)
			)
		)
		(pin "1"
		)
		(pin "2"
		)
		(instances
			(project "sdi-mipi-video-converter"
				(path ""
					(reference "C38")
					(unit 1)
				)
			)
		)
	)
	(symbol
		(lib_id "antmicropower:GND")
		(at 251.46 120.65 0)
		(unit 1)
		(exclude_from_sim no)
		(in_bom yes)
		(on_board yes)
		(dnp no)
		(fields_autoplaced yes)
		(property "Reference" "#PWR091"
			(at 260.35 123.19 0)
			(effects
				(font
					(size 1.27 1.27)
					(thickness 0.15)
				)
				(justify left bottom)
				(hide yes)
			)
		)
		(property "Value" "GND"
			(at 254 121.9199 0)
			(effects
				(font
					(size 1.27 1.27)
					(thickness 0.15)
				)
				(justify left)
			)
		)
		(property "Footprint" ""
			(at 260.35 128.27 0)
			(effects
				(font
					(size 1.27 1.27)
					(thickness 0.15)
				)
				(justify left bottom)
				(hide yes)
			)
		)
		(property "Datasheet" ""
			(at 260.35 133.35 0)
			(effects
				(font
					(size 1.27 1.27)
					(thickness 0.15)
				)
				(justify left bottom)
				(hide yes)
			)
		)
		(property "Description" ""
			(at 251.46 120.65 0)
			(effects
				(font
					(size 1.27 1.27)
				)
				(hide yes)
			)
		)
		(property "Author" "Antmicro"
			(at 260.35 128.27 0)
			(effects
				(font
					(size 1.27 1.27)
					(thickness 0.15)
				)
				(justify left bottom)
				(hide yes)
			)
		)
		(property "License" "Apache-2.0"
			(at 260.35 130.81 0)
			(effects
				(font
					(size 1.27 1.27)
					(thickness 0.15)
				)
				(justify left bottom)
				(hide yes)
			)
		)
		(pin "1"
		)
		(instances
			(project "sdi-mipi-video-converter"
				(path ""
					(reference "#PWR091")
					(unit 1)
				)
			)
		)
	)
	(symbol
		(lib_id "antmicroCapacitors0402:C_100n_0402")
		(at 313.69 119.38 90)
		(unit 1)
		(exclude_from_sim no)
		(in_bom yes)
		(on_board yes)
		(dnp no)
		(fields_autoplaced yes)
		(property "Reference" "C120"
			(at 316.23 115.5635 90)
			(effects
				(font
					(size 1.27 1.27)
					(thickness 0.15)
				)
				(justify right)
			)
		)
		(property "Value" "C_100n_0402"
			(at 323.85 99.06 0)
			(effects
				(font
					(size 1.27 1.27)
					(thickness 0.15)
				)
				(justify left bottom)
				(hide yes)
			)
		)
		(property "Footprint" "antmicro-footprints:C_0402_1005Metric"
			(at 326.39 99.06 0)
			(effects
				(font
					(size 1.27 1.27)
					(thickness 0.15)
				)
				(justify left bottom)
				(hide yes)
			)
		)
		(property "Datasheet" "https://www.murata.com/products/productdetail?partno=GRM155R61H104KE14%23"
			(at 328.93 99.06 0)
			(effects
				(font
					(size 1.27 1.27)
					(thickness 0.15)
				)
				(justify left bottom)
				(hide yes)
			)
		)
		(property "Description" "SMD Multilayer Ceramic Capacitor, 0.1 µF, 50 V, 0402 [1005 Metric], ± 10%, X5R, GRM Series"
			(at 313.69 119.38 0)
			(effects
				(font
					(size 1.27 1.27)
				)
				(hide yes)
			)
		)
		(property "Manufacturer" "Murata"
			(at 334.01 99.06 0)
			(effects
				(font
					(size 1.27 1.27)
					(thickness 0.15)
				)
				(justify left bottom)
				(hide yes)
			)
		)
		(property "MPN" "GRM155R61H104KE14D"
			(at 331.47 99.06 0)
			(effects
				(font
					(size 1.27 1.27)
					(thickness 0.15)
				)
				(justify left bottom)
				(hide yes)
			)
		)
		(property "Val" "100n"
			(at 316.23 118.1035 90)
			(effects
				(font
					(size 1.27 1.27)
					(thickness 0.15)
				)
				(justify right)
			)
		)
		(property "License" "Apache-2.0"
			(at 336.55 99.06 0)
			(effects
				(font
					(size 1.27 1.27)
					(thickness 0.15)
				)
				(justify left bottom)
				(hide yes)
			)
		)
		(property "Author" "Antmicro"
			(at 339.09 99.06 0)
			(effects
				(font
					(size 1.27 1.27)
					(thickness 0.15)
				)
				(justify left bottom)
				(hide yes)
			)
		)
		(property "Voltage" "50V"
			(at 341.63 99.06 0)
			(effects
				(font
					(size 1.27 1.27)
				)
				(justify left bottom)
				(hide yes)
			)
		)
		(property "Dielectric" "X5R"
			(at 344.17 99.06 0)
			(effects
				(font
					(size 1.27 1.27)
				)
				(justify left bottom)
				(hide yes)
			)
		)
		(pin "1"
		)
		(pin "2"
		)
		(instances
			(project "sdi-mipi-video-converter"
				(path ""
					(reference "C120")
					(unit 1)
				)
			)
		)
	)
	(symbol
		(lib_id "antmicroCapacitors0402:C_100n_0402")
		(at 314.96 109.22 90)
		(unit 1)
		(exclude_from_sim no)
		(in_bom yes)
		(on_board yes)
		(dnp no)
		(fields_autoplaced yes)
		(property "Reference" "C119"
			(at 317.5 105.4035 90)
			(effects
				(font
					(size 1.27 1.27)
					(thickness 0.15)
				)
				(justify right)
			)
		)
		(property "Value" "C_100n_0402"
			(at 325.12 88.9 0)
			(effects
				(font
					(size 1.27 1.27)
					(thickness 0.15)
				)
				(justify left bottom)
				(hide yes)
			)
		)
		(property "Footprint" "antmicro-footprints:C_0402_1005Metric"
			(at 327.66 88.9 0)
			(effects
				(font
					(size 1.27 1.27)
					(thickness 0.15)
				)
				(justify left bottom)
				(hide yes)
			)
		)
		(property "Datasheet" "https://www.murata.com/products/productdetail?partno=GRM155R61H104KE14%23"
			(at 330.2 88.9 0)
			(effects
				(font
					(size 1.27 1.27)
					(thickness 0.15)
				)
				(justify left bottom)
				(hide yes)
			)
		)
		(property "Description" "SMD Multilayer Ceramic Capacitor, 0.1 µF, 50 V, 0402 [1005 Metric], ± 10%, X5R, GRM Series"
			(at 314.96 109.22 0)
			(effects
				(font
					(size 1.27 1.27)
				)
				(hide yes)
			)
		)
		(property "Manufacturer" "Murata"
			(at 335.28 88.9 0)
			(effects
				(font
					(size 1.27 1.27)
					(thickness 0.15)
				)
				(justify left bottom)
				(hide yes)
			)
		)
		(property "MPN" "GRM155R61H104KE14D"
			(at 332.74 88.9 0)
			(effects
				(font
					(size 1.27 1.27)
					(thickness 0.15)
				)
				(justify left bottom)
				(hide yes)
			)
		)
		(property "Val" "100n"
			(at 317.5 107.9435 90)
			(effects
				(font
					(size 1.27 1.27)
					(thickness 0.15)
				)
				(justify right)
			)
		)
		(property "License" "Apache-2.0"
			(at 337.82 88.9 0)
			(effects
				(font
					(size 1.27 1.27)
					(thickness 0.15)
				)
				(justify left bottom)
				(hide yes)
			)
		)
		(property "Author" "Antmicro"
			(at 340.36 88.9 0)
			(effects
				(font
					(size 1.27 1.27)
					(thickness 0.15)
				)
				(justify left bottom)
				(hide yes)
			)
		)
		(property "Voltage" "50V"
			(at 342.9 88.9 0)
			(effects
				(font
					(size 1.27 1.27)
				)
				(justify left bottom)
				(hide yes)
			)
		)
		(property "Dielectric" "X5R"
			(at 345.44 88.9 0)
			(effects
				(font
					(size 1.27 1.27)
				)
				(justify left bottom)
				(hide yes)
			)
		)
		(pin "1"
		)
		(pin "2"
		)
		(instances
			(project "sdi-mipi-video-converter"
				(path ""
					(reference "C119")
					(unit 1)
				)
			)
		)
	)
	(symbol
		(lib_id "antmicroCapacitorsmisc:C_100n_0201")
		(at 120.65 46.99 90)
		(unit 1)
		(exclude_from_sim no)
		(in_bom yes)
		(on_board yes)
		(dnp no)
		(fields_autoplaced yes)
		(property "Reference" "C35"
			(at 123.19 43.1735 90)
			(effects
				(font
					(size 1.27 1.27)
					(thickness 0.15)
				)
				(justify right)
			)
		)
		(property "Value" "C_100n_0201"
			(at 130.81 26.67 0)
			(effects
				(font
					(size 1.27 1.27)
					(thickness 0.15)
				)
				(justify left bottom)
				(hide yes)
			)
		)
		(property "Footprint" "antmicro-footprints:C_0201"
			(at 133.35 26.67 0)
			(effects
				(font
					(size 1.27 1.27)
					(thickness 0.15)
				)
				(justify left bottom)
				(hide yes)
			)
		)
		(property "Datasheet" "https://www.yageo.com/en/Chart/Download/pdf/CC0201KRX6S5BB104"
			(at 135.89 26.67 0)
			(effects
				(font
					(size 1.27 1.27)
					(thickness 0.15)
				)
				(justify left bottom)
				(hide yes)
			)
		)
		(property "Description" "SMD Multilayer Ceramic Capacitor, 0.1 µF, 6.3 V, 0201 [0603 Metric], ± 10%, X6S, CC Series"
			(at 120.65 46.99 0)
			(effects
				(font
					(size 1.27 1.27)
				)
				(hide yes)
			)
		)
		(property "Manufacturer" "YAGEO"
			(at 140.97 26.67 0)
			(effects
				(font
					(size 1.27 1.27)
					(thickness 0.15)
				)
				(justify left bottom)
				(hide yes)
			)
		)
		(property "MPN" "CC0201KRX6S5BB104"
			(at 138.43 26.67 0)
			(effects
				(font
					(size 1.27 1.27)
					(thickness 0.15)
				)
				(justify left bottom)
				(hide yes)
			)
		)
		(property "Val" "100n"
			(at 123.19 45.7135 90)
			(effects
				(font
					(size 1.27 1.27)
					(thickness 0.15)
				)
				(justify right)
			)
		)
		(property "License" "Apache-2.0"
			(at 143.51 26.67 0)
			(effects
				(font
					(size 1.27 1.27)
					(thickness 0.15)
				)
				(justify left bottom)
				(hide yes)
			)
		)
		(property "Author" "Antmicro"
			(at 146.05 26.67 0)
			(effects
				(font
					(size 1.27 1.27)
					(thickness 0.15)
				)
				(justify left bottom)
				(hide yes)
			)
		)
		(property "Voltage" ""
			(at 148.59 26.67 0)
			(effects
				(font
					(size 1.27 1.27)
				)
				(justify left bottom)
				(hide yes)
			)
		)
		(property "Dielectric" ""
			(at 151.13 26.67 0)
			(effects
				(font
					(size 1.27 1.27)
				)
				(justify left bottom)
				(hide yes)
			)
		)
		(property "Public" "False"
			(at 153.67 26.67 0)
			(effects
				(font
					(size 1.27 1.27)
				)
				(justify left bottom)
				(hide yes)
			)
		)
		(pin "1"
		)
		(pin "2"
		)
		(instances
			(project "sdi-mipi-video-converter"
				(path ""
					(reference "C35")
					(unit 1)
				)
			)
		)
	)
	(symbol
		(lib_id "antmicropower:GND")
		(at 138.43 165.1 0)
		(mirror y)
		(unit 1)
		(exclude_from_sim no)
		(in_bom yes)
		(on_board yes)
		(dnp no)
		(fields_autoplaced yes)
		(property "Reference" "#PWR088"
			(at 129.54 167.64 0)
			(effects
				(font
					(size 1.27 1.27)
					(thickness 0.15)
				)
				(justify left bottom)
				(hide yes)
			)
		)
		(property "Value" "GND"
			(at 135.89 166.3699 0)
			(effects
				(font
					(size 1.27 1.27)
					(thickness 0.15)
				)
				(justify left)
			)
		)
		(property "Footprint" ""
			(at 129.54 172.72 0)
			(effects
				(font
					(size 1.27 1.27)
					(thickness 0.15)
				)
				(justify left bottom)
				(hide yes)
			)
		)
		(property "Datasheet" ""
			(at 129.54 177.8 0)
			(effects
				(font
					(size 1.27 1.27)
					(thickness 0.15)
				)
				(justify left bottom)
				(hide yes)
			)
		)
		(property "Description" ""
			(at 138.43 165.1 0)
			(effects
				(font
					(size 1.27 1.27)
				)
				(hide yes)
			)
		)
		(property "Author" "Antmicro"
			(at 129.54 172.72 0)
			(effects
				(font
					(size 1.27 1.27)
					(thickness 0.15)
				)
				(justify left bottom)
				(hide yes)
			)
		)
		(property "License" "Apache-2.0"
			(at 129.54 175.26 0)
			(effects
				(font
					(size 1.27 1.27)
					(thickness 0.15)
				)
				(justify left bottom)
				(hide yes)
			)
		)
		(pin "1"
		)
		(instances
			(project "sdi-mipi-video-converter"
				(path ""
					(reference "#PWR088")
					(unit 1)
				)
			)
		)
	)
	(symbol
		(lib_id "antmicroCapacitors0402:C_100n_0402")
		(at 307.34 86.36 90)
		(unit 1)
		(exclude_from_sim no)
		(in_bom yes)
		(on_board yes)
		(dnp no)
		(fields_autoplaced yes)
		(property "Reference" "C44"
			(at 309.88 82.5435 90)
			(effects
				(font
					(size 1.27 1.27)
					(thickness 0.15)
				)
				(justify right)
			)
		)
		(property "Value" "C_100n_0402"
			(at 317.5 66.04 0)
			(effects
				(font
					(size 1.27 1.27)
					(thickness 0.15)
				)
				(justify left bottom)
				(hide yes)
			)
		)
		(property "Footprint" "antmicro-footprints:C_0402_1005Metric"
			(at 320.04 66.04 0)
			(effects
				(font
					(size 1.27 1.27)
					(thickness 0.15)
				)
				(justify left bottom)
				(hide yes)
			)
		)
		(property "Datasheet" "https://www.murata.com/products/productdetail?partno=GRM155R61H104KE14%23"
			(at 322.58 66.04 0)
			(effects
				(font
					(size 1.27 1.27)
					(thickness 0.15)
				)
				(justify left bottom)
				(hide yes)
			)
		)
		(property "Description" "SMD Multilayer Ceramic Capacitor, 0.1 µF, 50 V, 0402 [1005 Metric], ± 10%, X5R, GRM Series"
			(at 307.34 86.36 0)
			(effects
				(font
					(size 1.27 1.27)
				)
				(hide yes)
			)
		)
		(property "Manufacturer" "Murata"
			(at 327.66 66.04 0)
			(effects
				(font
					(size 1.27 1.27)
					(thickness 0.15)
				)
				(justify left bottom)
				(hide yes)
			)
		)
		(property "MPN" "GRM155R61H104KE14D"
			(at 325.12 66.04 0)
			(effects
				(font
					(size 1.27 1.27)
					(thickness 0.15)
				)
				(justify left bottom)
				(hide yes)
			)
		)
		(property "Val" "100n"
			(at 309.88 85.0835 90)
			(effects
				(font
					(size 1.27 1.27)
					(thickness 0.15)
				)
				(justify right)
			)
		)
		(property "License" "Apache-2.0"
			(at 330.2 66.04 0)
			(effects
				(font
					(size 1.27 1.27)
					(thickness 0.15)
				)
				(justify left bottom)
				(hide yes)
			)
		)
		(property "Author" "Antmicro"
			(at 332.74 66.04 0)
			(effects
				(font
					(size 1.27 1.27)
					(thickness 0.15)
				)
				(justify left bottom)
				(hide yes)
			)
		)
		(property "Voltage" "50V"
			(at 335.28 66.04 0)
			(effects
				(font
					(size 1.27 1.27)
				)
				(justify left bottom)
				(hide yes)
			)
		)
		(property "Dielectric" "X5R"
			(at 337.82 66.04 0)
			(effects
				(font
					(size 1.27 1.27)
				)
				(justify left bottom)
				(hide yes)
			)
		)
		(pin "1"
		)
		(pin "2"
		)
		(instances
			(project "sdi-mipi-video-converter"
				(path ""
					(reference "C44")
					(unit 1)
				)
			)
		)
	)
	(symbol
		(lib_id "antmicroCapacitors0402:C_100n_0402")
		(at 328.93 119.38 90)
		(unit 1)
		(exclude_from_sim no)
		(in_bom yes)
		(on_board yes)
		(dnp no)
		(fields_autoplaced yes)
		(property "Reference" "C50"
			(at 331.47 115.5635 90)
			(effects
				(font
					(size 1.27 1.27)
					(thickness 0.15)
				)
				(justify right)
			)
		)
		(property "Value" "C_100n_0402"
			(at 339.09 99.06 0)
			(effects
				(font
					(size 1.27 1.27)
					(thickness 0.15)
				)
				(justify left bottom)
				(hide yes)
			)
		)
		(property "Footprint" "antmicro-footprints:C_0402_1005Metric"
			(at 341.63 99.06 0)
			(effects
				(font
					(size 1.27 1.27)
					(thickness 0.15)
				)
				(justify left bottom)
				(hide yes)
			)
		)
		(property "Datasheet" "https://www.murata.com/products/productdetail?partno=GRM155R61H104KE14%23"
			(at 344.17 99.06 0)
			(effects
				(font
					(size 1.27 1.27)
					(thickness 0.15)
				)
				(justify left bottom)
				(hide yes)
			)
		)
		(property "Description" "SMD Multilayer Ceramic Capacitor, 0.1 µF, 50 V, 0402 [1005 Metric], ± 10%, X5R, GRM Series"
			(at 328.93 119.38 0)
			(effects
				(font
					(size 1.27 1.27)
				)
				(hide yes)
			)
		)
		(property "Manufacturer" "Murata"
			(at 349.25 99.06 0)
			(effects
				(font
					(size 1.27 1.27)
					(thickness 0.15)
				)
				(justify left bottom)
				(hide yes)
			)
		)
		(property "MPN" "GRM155R61H104KE14D"
			(at 346.71 99.06 0)
			(effects
				(font
					(size 1.27 1.27)
					(thickness 0.15)
				)
				(justify left bottom)
				(hide yes)
			)
		)
		(property "Val" "100n"
			(at 331.47 118.1035 90)
			(effects
				(font
					(size 1.27 1.27)
					(thickness 0.15)
				)
				(justify right)
			)
		)
		(property "License" "Apache-2.0"
			(at 351.79 99.06 0)
			(effects
				(font
					(size 1.27 1.27)
					(thickness 0.15)
				)
				(justify left bottom)
				(hide yes)
			)
		)
		(property "Author" "Antmicro"
			(at 354.33 99.06 0)
			(effects
				(font
					(size 1.27 1.27)
					(thickness 0.15)
				)
				(justify left bottom)
				(hide yes)
			)
		)
		(property "Voltage" "50V"
			(at 356.87 99.06 0)
			(effects
				(font
					(size 1.27 1.27)
				)
				(justify left bottom)
				(hide yes)
			)
		)
		(property "Dielectric" "X5R"
			(at 359.41 99.06 0)
			(effects
				(font
					(size 1.27 1.27)
				)
				(justify left bottom)
				(hide yes)
			)
		)
		(pin "1"
		)
		(pin "2"
		)
		(instances
			(project "sdi-mipi-video-converter"
				(path ""
					(reference "C50")
					(unit 1)
				)
			)
		)
	)
	(symbol
		(lib_id "antmicroCapacitorsmisc:C_100n_0201")
		(at 125.73 158.75 270)
		(unit 1)
		(exclude_from_sim no)
		(in_bom yes)
		(on_board yes)
		(dnp no)
		(fields_autoplaced yes)
		(property "Reference" "C36"
			(at 128.27 160.0262 90)
			(effects
				(font
					(size 1.27 1.27)
					(thickness 0.15)
				)
				(justify left)
			)
		)
		(property "Value" "C_100n_0201"
			(at 115.57 179.07 0)
			(effects
				(font
					(size 1.27 1.27)
					(thickness 0.15)
				)
				(justify left bottom)
				(hide yes)
			)
		)
		(property "Footprint" "antmicro-footprints:C_0201"
			(at 113.03 179.07 0)
			(effects
				(font
					(size 1.27 1.27)
					(thickness 0.15)
				)
				(justify left bottom)
				(hide yes)
			)
		)
		(property "Datasheet" "https://www.yageo.com/en/Chart/Download/pdf/CC0201KRX6S5BB104"
			(at 110.49 179.07 0)
			(effects
				(font
					(size 1.27 1.27)
					(thickness 0.15)
				)
				(justify left bottom)
				(hide yes)
			)
		)
		(property "Description" "SMD Multilayer Ceramic Capacitor, 0.1 µF, 6.3 V, 0201 [0603 Metric], ± 10%, X6S, CC Series"
			(at 125.73 158.75 0)
			(effects
				(font
					(size 1.27 1.27)
				)
				(hide yes)
			)
		)
		(property "Manufacturer" "YAGEO"
			(at 105.41 179.07 0)
			(effects
				(font
					(size 1.27 1.27)
					(thickness 0.15)
				)
				(justify left bottom)
				(hide yes)
			)
		)
		(property "MPN" "CC0201KRX6S5BB104"
			(at 107.95 179.07 0)
			(effects
				(font
					(size 1.27 1.27)
					(thickness 0.15)
				)
				(justify left bottom)
				(hide yes)
			)
		)
		(property "Val" "100n"
			(at 128.27 162.5662 90)
			(effects
				(font
					(size 1.27 1.27)
					(thickness 0.15)
				)
				(justify left)
			)
		)
		(property "License" "Apache-2.0"
			(at 102.87 179.07 0)
			(effects
				(font
					(size 1.27 1.27)
					(thickness 0.15)
				)
				(justify left bottom)
				(hide yes)
			)
		)
		(property "Author" "Antmicro"
			(at 100.33 179.07 0)
			(effects
				(font
					(size 1.27 1.27)
					(thickness 0.15)
				)
				(justify left bottom)
				(hide yes)
			)
		)
		(property "Voltage" ""
			(at 97.79 179.07 0)
			(effects
				(font
					(size 1.27 1.27)
				)
				(justify left bottom)
				(hide yes)
			)
		)
		(property "Dielectric" ""
			(at 95.25 179.07 0)
			(effects
				(font
					(size 1.27 1.27)
				)
				(justify left bottom)
				(hide yes)
			)
		)
		(property "Public" "False"
			(at 92.71 179.07 0)
			(effects
				(font
					(size 1.27 1.27)
				)
				(justify left bottom)
				(hide yes)
			)
		)
		(pin "1"
		)
		(pin "2"
		)
		(instances
			(project "sdi-mipi-video-converter"
				(path ""
					(reference "C36")
					(unit 1)
				)
			)
		)
	)
	(symbol
		(lib_id "antmicroCapacitorsmisc:C_100n_0201")
		(at 115.57 163.83 90)
		(unit 1)
		(exclude_from_sim no)
		(in_bom yes)
		(on_board yes)
		(dnp no)
		(fields_autoplaced yes)
		(property "Reference" "C16"
			(at 118.11 160.0135 90)
			(effects
				(font
					(size 1.27 1.27)
					(thickness 0.15)
				)
				(justify right)
			)
		)
		(property "Value" "C_100n_0201"
			(at 125.73 143.51 0)
			(effects
				(font
					(size 1.27 1.27)
					(thickness 0.15)
				)
				(justify left bottom)
				(hide yes)
			)
		)
		(property "Footprint" "antmicro-footprints:C_0201"
			(at 128.27 143.51 0)
			(effects
				(font
					(size 1.27 1.27)
					(thickness 0.15)
				)
				(justify left bottom)
				(hide yes)
			)
		)
		(property "Datasheet" "https://www.yageo.com/en/Chart/Download/pdf/CC0201KRX6S5BB104"
			(at 130.81 143.51 0)
			(effects
				(font
					(size 1.27 1.27)
					(thickness 0.15)
				)
				(justify left bottom)
				(hide yes)
			)
		)
		(property "Description" "SMD Multilayer Ceramic Capacitor, 0.1 µF, 6.3 V, 0201 [0603 Metric], ± 10%, X6S, CC Series"
			(at 115.57 163.83 0)
			(effects
				(font
					(size 1.27 1.27)
				)
				(hide yes)
			)
		)
		(property "Manufacturer" "YAGEO"
			(at 135.89 143.51 0)
			(effects
				(font
					(size 1.27 1.27)
					(thickness 0.15)
				)
				(justify left bottom)
				(hide yes)
			)
		)
		(property "MPN" "CC0201KRX6S5BB104"
			(at 133.35 143.51 0)
			(effects
				(font
					(size 1.27 1.27)
					(thickness 0.15)
				)
				(justify left bottom)
				(hide yes)
			)
		)
		(property "Val" "100n"
			(at 118.11 162.5535 90)
			(effects
				(font
					(size 1.27 1.27)
					(thickness 0.15)
				)
				(justify right)
			)
		)
		(property "License" "Apache-2.0"
			(at 138.43 143.51 0)
			(effects
				(font
					(size 1.27 1.27)
					(thickness 0.15)
				)
				(justify left bottom)
				(hide yes)
			)
		)
		(property "Author" "Antmicro"
			(at 140.97 143.51 0)
			(effects
				(font
					(size 1.27 1.27)
					(thickness 0.15)
				)
				(justify left bottom)
				(hide yes)
			)
		)
		(property "Voltage" ""
			(at 143.51 143.51 0)
			(effects
				(font
					(size 1.27 1.27)
				)
				(justify left bottom)
				(hide yes)
			)
		)
		(property "Dielectric" ""
			(at 146.05 143.51 0)
			(effects
				(font
					(size 1.27 1.27)
				)
				(justify left bottom)
				(hide yes)
			)
		)
		(property "Public" "False"
			(at 148.59 143.51 0)
			(effects
				(font
					(size 1.27 1.27)
				)
				(justify left bottom)
				(hide yes)
			)
		)
		(pin "1"
		)
		(pin "2"
		)
		(instances
			(project "sdi-mipi-video-converter"
				(path ""
					(reference "C16")
					(unit 1)
				)
			)
		)
	)
	(symbol
		(lib_id "antmicropower:+1V5")
		(at 137.16 147.32 0)
		(unit 1)
		(exclude_from_sim no)
		(in_bom yes)
		(on_board yes)
		(dnp no)
		(fields_autoplaced yes)
		(property "Reference" "#PWR0230"
			(at 137.16 151.13 0)
			(effects
				(font
					(size 1.27 1.27)
				)
				(hide yes)
			)
		)
		(property "Value" "+1V5"
			(at 137.16 142.24 0)
			(effects
				(font
					(size 1.27 1.27)
				)
			)
		)
		(property "Footprint" ""
			(at 137.16 147.32 0)
			(effects
				(font
					(size 1.27 1.27)
				)
				(hide yes)
			)
		)
		(property "Datasheet" ""
			(at 137.16 147.32 0)
			(effects
				(font
					(size 1.27 1.27)
				)
				(hide yes)
			)
		)
		(property "Description" ""
			(at 137.16 147.32 0)
			(effects
				(font
					(size 1.27 1.27)
				)
				(hide yes)
			)
		)
		(pin "1"
		)
		(instances
			(project "sdi-mipi-video-converter"
				(path ""
					(reference "#PWR0230")
					(unit 1)
				)
			)
		)
	)
	(symbol
		(lib_id "antmicroFPGAChips:CrossLink_LIFCL-40-9BG256C")
		(at 92.71 35.56 0)
		(mirror y)
		(unit 4)
		(exclude_from_sim no)
		(in_bom yes)
		(on_board yes)
		(dnp no)
		(fields_autoplaced yes)
		(property "Reference" "U11"
			(at 69.85 27.94 0)
			(effects
				(font
					(size 1.27 1.27)
					(thickness 0.15)
				)
			)
		)
		(property "Value" "LIFCL-40-9BG256C"
			(at 69.85 27.94 0)
			(effects
				(font
					(size 1.27 1.27)
					(thickness 0.15)
				)
				(hide yes)
			)
		)
		(property "Footprint" "antmicro-footprints:BGA-256_14x14mm_Layout16x16_P0.8mm"
			(at 39.37 43.18 0)
			(effects
				(font
					(size 1.27 1.27)
					(thickness 0.15)
				)
				(justify left bottom)
				(hide yes)
			)
		)
		(property "Datasheet" "https://www.latticesemi.com/-/media/LatticeSemi/Documents/DataSheets/CrossLink/FPGA-DS-02007-2-1-CrossLink-Family-Data-Sheet.ashx?document_id=51662"
			(at 39.37 45.72 0)
			(effects
				(font
					(size 1.27 1.27)
					(thickness 0.15)
				)
				(justify left bottom)
				(hide yes)
			)
		)
		(property "Description" "CrossLink-NX™ Field Programmable Gate Array 256-LFBGA"
			(at 92.71 35.56 0)
			(effects
				(font
					(size 1.27 1.27)
				)
				(hide yes)
			)
		)
		(property "MPN" "LIFCL-40-9BG256C"
			(at 69.85 30.48 0)
			(effects
				(font
					(size 1.27 1.27)
					(thickness 0.15)
				)
			)
		)
		(property "Manufacturer" "Lattice Semiconductor"
			(at 39.37 48.26 0)
			(effects
				(font
					(size 1.27 1.27)
					(thickness 0.15)
				)
				(justify left bottom)
				(hide yes)
			)
		)
		(property "Author" "Antmicro"
			(at 39.37 50.8 0)
			(effects
				(font
					(size 1.27 1.27)
					(thickness 0.15)
				)
				(justify left bottom)
				(hide yes)
			)
		)
		(property "License" "Apache-2.0"
			(at 39.37 53.34 0)
			(effects
				(font
					(size 1.27 1.27)
					(thickness 0.15)
				)
				(justify left bottom)
				(hide yes)
			)
		)
		(pin "B16"
		)
		(pin "C12"
		)
		(pin "C13"
		)
		(pin "C14"
		)
		(pin "C15"
		)
		(pin "C16"
		)
		(pin "D11"
		)
		(pin "D12"
		)
		(pin "D13"
		)
		(pin "D15"
		)
		(pin "D16"
		)
		(pin "E15"
		)
		(pin "E16"
		)
		(pin "D10"
		)
		(pin "E10"
		)
		(pin "E11"
		)
		(pin "E12"
		)
		(pin "E13"
		)
		(pin "E14"
		)
		(pin "E9"
		)
		(pin "F10"
		)
		(pin "F11"
		)
		(pin "F13"
		)
		(pin "F14"
		)
		(pin "F15"
		)
		(pin "F16"
		)
		(pin "F9"
		)
		(pin "G10"
		)
		(pin "G11"
		)
		(pin "G12"
		)
		(pin "G13"
		)
		(pin "G14"
		)
		(pin "G15"
		)
		(pin "G16"
		)
		(pin "G9"
		)
		(pin "H10"
		)
		(pin "H11"
		)
		(pin "H12"
		)
		(pin "H13"
		)
		(pin "H14"
		)
		(pin "H15"
		)
		(pin "H16"
		)
		(pin "J11"
		)
		(pin "J12"
		)
		(pin "J13"
		)
		(pin "J15"
		)
		(pin "J16"
		)
		(pin "K11"
		)
		(pin "K12"
		)
		(pin "L10"
		)
		(pin "L11"
		)
		(pin "L12"
		)
		(pin "M11"
		)
		(pin "M12"
		)
		(pin "M13"
		)
		(pin "M14"
		)
		(pin "M15"
		)
		(pin "M16"
		)
		(pin "N11"
		)
		(pin "N12"
		)
		(pin "N13"
		)
		(pin "N14"
		)
		(pin "N15"
		)
		(pin "N16"
		)
		(pin "P10"
		)
		(pin "P11"
		)
		(pin "P12"
		)
		(pin "P14"
		)
		(pin "P15"
		)
		(pin "P16"
		)
		(pin "R10"
		)
		(pin "R11"
		)
		(pin "R12"
		)
		(pin "R13"
		)
		(pin "R14"
		)
		(pin "R15"
		)
		(pin "R16"
		)
		(pin "T11"
		)
		(pin "T12"
		)
		(pin "T13"
		)
		(pin "T14"
		)
		(pin "T15"
		)
		(pin "L8"
		)
		(pin "L9"
		)
		(pin "M10"
		)
		(pin "M8"
		)
		(pin "M9"
		)
		(pin "N10"
		)
		(pin "N6"
		)
		(pin "N8"
		)
		(pin "N9"
		)
		(pin "P4"
		)
		(pin "P5"
		)
		(pin "P6"
		)
		(pin "P7"
		)
		(pin "P8"
		)
		(pin "P9"
		)
		(pin "R1"
		)
		(pin "R2"
		)
		(pin "R3"
		)
		(pin "R4"
		)
		(pin "R5"
		)
		(pin "R6"
		)
		(pin "R7"
		)
		(pin "R8"
		)
		(pin "R9"
		)
		(pin "T10"
		)
		(pin "T2"
		)
		(pin "T3"
		)
		(pin "T4"
		)
		(pin "T5"
		)
		(pin "T6"
		)
		(pin "T7"
		)
		(pin "T8"
		)
		(pin "T9"
		)
		(pin "K7"
		)
		(pin "L6"
		)
		(pin "L7"
		)
		(pin "M4"
		)
		(pin "M7"
		)
		(pin "N3"
		)
		(pin "N4"
		)
		(pin "N5"
		)
		(pin "P1"
		)
		(pin "P2"
		)
		(pin "P3"
		)
		(pin "H1"
		)
		(pin "H2"
		)
		(pin "H3"
		)
		(pin "H4"
		)
		(pin "H5"
		)
		(pin "H6"
		)
		(pin "J1"
		)
		(pin "J2"
		)
		(pin "J4"
		)
		(pin "J5"
		)
		(pin "J6"
		)
		(pin "K1"
		)
		(pin "K2"
		)
		(pin "K3"
		)
		(pin "K4"
		)
		(pin "K5"
		)
		(pin "K6"
		)
		(pin "L1"
		)
		(pin "L2"
		)
		(pin "L3"
		)
		(pin "L4"
		)
		(pin "L5"
		)
		(pin "M1"
		)
		(pin "M2"
		)
		(pin "M3"
		)
		(pin "N1"
		)
		(pin "N2"
		)
		(pin "D4"
		)
		(pin "D5"
		)
		(pin "D6"
		)
		(pin "E4"
		)
		(pin "E5"
		)
		(pin "E6"
		)
		(pin "F4"
		)
		(pin "F5"
		)
		(pin "F6"
		)
		(pin "G3"
		)
		(pin "G4"
		)
		(pin "G6"
		)
		(pin "B1"
		)
		(pin "B2"
		)
		(pin "C1"
		)
		(pin "C2"
		)
		(pin "D1"
		)
		(pin "D2"
		)
		(pin "E1"
		)
		(pin "E2"
		)
		(pin "F1"
		)
		(pin "F2"
		)
		(pin "A3"
		)
		(pin "A4"
		)
		(pin "A5"
		)
		(pin "A6"
		)
		(pin "A7"
		)
		(pin "B3"
		)
		(pin "B4"
		)
		(pin "B5"
		)
		(pin "B6"
		)
		(pin "B7"
		)
		(pin "K13"
		)
		(pin "K14"
		)
		(pin "K15"
		)
		(pin "K16"
		)
		(pin "L13"
		)
		(pin "L14"
		)
		(pin "L15"
		)
		(pin "L16"
		)
		(pin "A11"
		)
		(pin "A12"
		)
		(pin "A14"
		)
		(pin "A15"
		)
		(pin "A9"
		)
		(pin "B12"
		)
		(pin "B9"
		)
		(pin "C11"
		)
		(pin "A1"
		)
		(pin "A10"
		)
		(pin "A13"
		)
		(pin "A16"
		)
		(pin "A2"
		)
		(pin "A8"
		)
		(pin "B10"
		)
		(pin "B11"
		)
		(pin "B13"
		)
		(pin "B14"
		)
		(pin "B15"
		)
		(pin "B8"
		)
		(pin "C10"
		)
		(pin "C3"
		)
		(pin "C4"
		)
		(pin "C5"
		)
		(pin "C6"
		)
		(pin "C7"
		)
		(pin "C8"
		)
		(pin "C9"
		)
		(pin "D14"
		)
		(pin "D3"
		)
		(pin "D7"
		)
		(pin "D8"
		)
		(pin "D9"
		)
		(pin "E3"
		)
		(pin "E7"
		)
		(pin "E8"
		)
		(pin "F12"
		)
		(pin "F3"
		)
		(pin "F7"
		)
		(pin "F8"
		)
		(pin "G1"
		)
		(pin "G2"
		)
		(pin "G5"
		)
		(pin "G7"
		)
		(pin "G8"
		)
		(pin "H7"
		)
		(pin "H8"
		)
		(pin "H9"
		)
		(pin "J10"
		)
		(pin "J14"
		)
		(pin "J3"
		)
		(pin "J7"
		)
		(pin "J8"
		)
		(pin "J9"
		)
		(pin "K10"
		)
		(pin "K8"
		)
		(pin "K9"
		)
		(pin "M5"
		)
		(pin "M6"
		)
		(pin "N7"
		)
		(pin "P13"
		)
		(pin "T1"
		)
		(pin "T16"
		)
		(instances
			(project "sdi-mipi-video-converter"
				(path ""
					(reference "U11")
					(unit 4)
				)
			)
		)
	)
	(symbol
		(lib_id "antmicroCapacitorsmisc:C_100n_0201")
		(at 137.16 153.67 90)
		(unit 1)
		(exclude_from_sim no)
		(in_bom yes)
		(on_board yes)
		(dnp no)
		(fields_autoplaced yes)
		(property "Reference" "C37"
			(at 139.7 149.8535 90)
			(effects
				(font
					(size 1.27 1.27)
					(thickness 0.15)
				)
				(justify right)
			)
		)
		(property "Value" "C_100n_0201"
			(at 147.32 133.35 0)
			(effects
				(font
					(size 1.27 1.27)
					(thickness 0.15)
				)
				(justify left bottom)
				(hide yes)
			)
		)
		(property "Footprint" "antmicro-footprints:C_0201"
			(at 149.86 133.35 0)
			(effects
				(font
					(size 1.27 1.27)
					(thickness 0.15)
				)
				(justify left bottom)
				(hide yes)
			)
		)
		(property "Datasheet" "https://www.yageo.com/en/Chart/Download/pdf/CC0201KRX6S5BB104"
			(at 152.4 133.35 0)
			(effects
				(font
					(size 1.27 1.27)
					(thickness 0.15)
				)
				(justify left bottom)
				(hide yes)
			)
		)
		(property "Description" "SMD Multilayer Ceramic Capacitor, 0.1 µF, 6.3 V, 0201 [0603 Metric], ± 10%, X6S, CC Series"
			(at 137.16 153.67 0)
			(effects
				(font
					(size 1.27 1.27)
				)
				(hide yes)
			)
		)
		(property "Manufacturer" "YAGEO"
			(at 157.48 133.35 0)
			(effects
				(font
					(size 1.27 1.27)
					(thickness 0.15)
				)
				(justify left bottom)
				(hide yes)
			)
		)
		(property "MPN" "CC0201KRX6S5BB104"
			(at 154.94 133.35 0)
			(effects
				(font
					(size 1.27 1.27)
					(thickness 0.15)
				)
				(justify left bottom)
				(hide yes)
			)
		)
		(property "Val" "100n"
			(at 139.7 152.3935 90)
			(effects
				(font
					(size 1.27 1.27)
					(thickness 0.15)
				)
				(justify right)
			)
		)
		(property "License" "Apache-2.0"
			(at 160.02 133.35 0)
			(effects
				(font
					(size 1.27 1.27)
					(thickness 0.15)
				)
				(justify left bottom)
				(hide yes)
			)
		)
		(property "Author" "Antmicro"
			(at 162.56 133.35 0)
			(effects
				(font
					(size 1.27 1.27)
					(thickness 0.15)
				)
				(justify left bottom)
				(hide yes)
			)
		)
		(property "Voltage" ""
			(at 165.1 133.35 0)
			(effects
				(font
					(size 1.27 1.27)
				)
				(justify left bottom)
				(hide yes)
			)
		)
		(property "Dielectric" ""
			(at 167.64 133.35 0)
			(effects
				(font
					(size 1.27 1.27)
				)
				(justify left bottom)
				(hide yes)
			)
		)
		(property "Public" "False"
			(at 170.18 133.35 0)
			(effects
				(font
					(size 1.27 1.27)
				)
				(justify left bottom)
				(hide yes)
			)
		)
		(pin "1"
		)
		(pin "2"
		)
		(instances
			(project "sdi-mipi-video-converter"
				(path ""
					(reference "C37")
					(unit 1)
				)
			)
		)
	)
	(symbol
		(lib_id "antmicropower:+1V5")
		(at 130.81 29.21 0)
		(unit 1)
		(exclude_from_sim no)
		(in_bom yes)
		(on_board yes)
		(dnp no)
		(fields_autoplaced yes)
		(property "Reference" "#PWR0231"
			(at 130.81 33.02 0)
			(effects
				(font
					(size 1.27 1.27)
				)
				(hide yes)
			)
		)
		(property "Value" "+1V5"
			(at 130.81 24.13 0)
			(effects
				(font
					(size 1.27 1.27)
				)
			)
		)
		(property "Footprint" ""
			(at 130.81 29.21 0)
			(effects
				(font
					(size 1.27 1.27)
				)
				(hide yes)
			)
		)
		(property "Datasheet" ""
			(at 130.81 29.21 0)
			(effects
				(font
					(size 1.27 1.27)
				)
				(hide yes)
			)
		)
		(property "Description" ""
			(at 130.81 29.21 0)
			(effects
				(font
					(size 1.27 1.27)
				)
				(hide yes)
			)
		)
		(pin "1"
		)
		(instances
			(project "sdi-mipi-video-converter"
				(path ""
					(reference "#PWR0231")
					(unit 1)
				)
			)
		)
	)
	(symbol
		(lib_id "antmicroCapacitors0402:C_100n_0402")
		(at 307.34 62.23 90)
		(unit 1)
		(exclude_from_sim no)
		(in_bom yes)
		(on_board yes)
		(dnp no)
		(fields_autoplaced yes)
		(property "Reference" "C43"
			(at 309.88 58.4135 90)
			(effects
				(font
					(size 1.27 1.27)
					(thickness 0.15)
				)
				(justify right)
			)
		)
		(property "Value" "C_100n_0402"
			(at 317.5 41.91 0)
			(effects
				(font
					(size 1.27 1.27)
					(thickness 0.15)
				)
				(justify left bottom)
				(hide yes)
			)
		)
		(property "Footprint" "antmicro-footprints:C_0402_1005Metric"
			(at 320.04 41.91 0)
			(effects
				(font
					(size 1.27 1.27)
					(thickness 0.15)
				)
				(justify left bottom)
				(hide yes)
			)
		)
		(property "Datasheet" "https://www.murata.com/products/productdetail?partno=GRM155R61H104KE14%23"
			(at 322.58 41.91 0)
			(effects
				(font
					(size 1.27 1.27)
					(thickness 0.15)
				)
				(justify left bottom)
				(hide yes)
			)
		)
		(property "Description" "SMD Multilayer Ceramic Capacitor, 0.1 µF, 50 V, 0402 [1005 Metric], ± 10%, X5R, GRM Series"
			(at 307.34 62.23 0)
			(effects
				(font
					(size 1.27 1.27)
				)
				(hide yes)
			)
		)
		(property "Manufacturer" "Murata"
			(at 327.66 41.91 0)
			(effects
				(font
					(size 1.27 1.27)
					(thickness 0.15)
				)
				(justify left bottom)
				(hide yes)
			)
		)
		(property "MPN" "GRM155R61H104KE14D"
			(at 325.12 41.91 0)
			(effects
				(font
					(size 1.27 1.27)
					(thickness 0.15)
				)
				(justify left bottom)
				(hide yes)
			)
		)
		(property "Val" "100n"
			(at 309.88 60.9535 90)
			(effects
				(font
					(size 1.27 1.27)
					(thickness 0.15)
				)
				(justify right)
			)
		)
		(property "License" "Apache-2.0"
			(at 330.2 41.91 0)
			(effects
				(font
					(size 1.27 1.27)
					(thickness 0.15)
				)
				(justify left bottom)
				(hide yes)
			)
		)
		(property "Author" "Antmicro"
			(at 332.74 41.91 0)
			(effects
				(font
					(size 1.27 1.27)
					(thickness 0.15)
				)
				(justify left bottom)
				(hide yes)
			)
		)
		(property "Voltage" "50V"
			(at 335.28 41.91 0)
			(effects
				(font
					(size 1.27 1.27)
				)
				(justify left bottom)
				(hide yes)
			)
		)
		(property "Dielectric" "X5R"
			(at 337.82 41.91 0)
			(effects
				(font
					(size 1.27 1.27)
				)
				(justify left bottom)
				(hide yes)
			)
		)
		(pin "1"
		)
		(pin "2"
		)
		(instances
			(project "sdi-mipi-video-converter"
				(path ""
					(reference "C43")
					(unit 1)
				)
			)
		)
	)
	(symbol
		(lib_id "antmicropower:GND")
		(at 346.71 95.25 0)
		(unit 1)
		(exclude_from_sim no)
		(in_bom yes)
		(on_board yes)
		(dnp no)
		(fields_autoplaced yes)
		(property "Reference" "#PWR0105"
			(at 355.6 97.79 0)
			(effects
				(font
					(size 1.27 1.27)
					(thickness 0.15)
				)
				(justify left bottom)
				(hide yes)
			)
		)
		(property "Value" "GND"
			(at 346.71 100.33 0)
			(effects
				(font
					(size 1.27 1.27)
					(thickness 0.15)
				)
			)
		)
		(property "Footprint" ""
			(at 355.6 102.87 0)
			(effects
				(font
					(size 1.27 1.27)
					(thickness 0.15)
				)
				(justify left bottom)
				(hide yes)
			)
		)
		(property "Datasheet" ""
			(at 355.6 107.95 0)
			(effects
				(font
					(size 1.27 1.27)
					(thickness 0.15)
				)
				(justify left bottom)
				(hide yes)
			)
		)
		(property "Description" ""
			(at 346.71 95.25 0)
			(effects
				(font
					(size 1.27 1.27)
				)
				(hide yes)
			)
		)
		(property "Author" "Antmicro"
			(at 355.6 102.87 0)
			(effects
				(font
					(size 1.27 1.27)
					(thickness 0.15)
				)
				(justify left bottom)
				(hide yes)
			)
		)
		(property "License" "Apache-2.0"
			(at 355.6 105.41 0)
			(effects
				(font
					(size 1.27 1.27)
					(thickness 0.15)
				)
				(justify left bottom)
				(hide yes)
			)
		)
		(pin "1"
		)
		(instances
			(project "sdi-mipi-video-converter"
				(path ""
					(reference "#PWR0105")
					(unit 1)
				)
			)
		)
	)
	(symbol
		(lib_id "antmicropower:+1V5")
		(at 330.2 102.87 0)
		(unit 1)
		(exclude_from_sim no)
		(in_bom yes)
		(on_board yes)
		(dnp no)
		(fields_autoplaced yes)
		(property "Reference" "#PWR0234"
			(at 330.2 106.68 0)
			(effects
				(font
					(size 1.27 1.27)
				)
				(hide yes)
			)
		)
		(property "Value" "+1V5"
			(at 330.2 97.79 0)
			(effects
				(font
					(size 1.27 1.27)
				)
			)
		)
		(property "Footprint" ""
			(at 330.2 102.87 0)
			(effects
				(font
					(size 1.27 1.27)
				)
				(hide yes)
			)
		)
		(property "Datasheet" ""
			(at 330.2 102.87 0)
			(effects
				(font
					(size 1.27 1.27)
				)
				(hide yes)
			)
		)
		(property "Description" ""
			(at 330.2 102.87 0)
			(effects
				(font
					(size 1.27 1.27)
				)
				(hide yes)
			)
		)
		(pin "1"
		)
		(instances
			(project "sdi-mipi-video-converter"
				(path ""
					(reference "#PWR0234")
					(unit 1)
				)
			)
		)
	)
	(symbol
		(lib_id "antmicropower:GND")
		(at 115.57 165.1 0)
		(unit 1)
		(exclude_from_sim no)
		(in_bom yes)
		(on_board yes)
		(dnp no)
		(fields_autoplaced yes)
		(property "Reference" "#PWR084"
			(at 124.46 167.64 0)
			(effects
				(font
					(size 1.27 1.27)
					(thickness 0.15)
				)
				(justify left bottom)
				(hide yes)
			)
		)
		(property "Value" "GND"
			(at 115.57 170.18 0)
			(effects
				(font
					(size 1.27 1.27)
					(thickness 0.15)
				)
			)
		)
		(property "Footprint" ""
			(at 124.46 172.72 0)
			(effects
				(font
					(size 1.27 1.27)
					(thickness 0.15)
				)
				(justify left bottom)
				(hide yes)
			)
		)
		(property "Datasheet" ""
			(at 124.46 177.8 0)
			(effects
				(font
					(size 1.27 1.27)
					(thickness 0.15)
				)
				(justify left bottom)
				(hide yes)
			)
		)
		(property "Description" ""
			(at 115.57 165.1 0)
			(effects
				(font
					(size 1.27 1.27)
				)
				(hide yes)
			)
		)
		(property "Author" "Antmicro"
			(at 124.46 172.72 0)
			(effects
				(font
					(size 1.27 1.27)
					(thickness 0.15)
				)
				(justify left bottom)
				(hide yes)
			)
		)
		(property "License" "Apache-2.0"
			(at 124.46 175.26 0)
			(effects
				(font
					(size 1.27 1.27)
					(thickness 0.15)
				)
				(justify left bottom)
				(hide yes)
			)
		)
		(pin "1"
		)
		(instances
			(project "sdi-mipi-video-converter"
				(path ""
					(reference "#PWR084")
					(unit 1)
				)
			)
		)
	)
	(symbol
		(lib_id "antmicroCapacitors0402:C_100n_0402")
		(at 328.93 86.36 270)
		(mirror x)
		(unit 1)
		(exclude_from_sim no)
		(in_bom yes)
		(on_board yes)
		(dnp no)
		(fields_autoplaced yes)
		(property "Reference" "C48"
			(at 331.47 82.5435 90)
			(effects
				(font
					(size 1.27 1.27)
					(thickness 0.15)
				)
				(justify left)
			)
		)
		(property "Value" "C_100n_0402"
			(at 318.77 66.04 0)
			(effects
				(font
					(size 1.27 1.27)
					(thickness 0.15)
				)
				(justify left bottom)
				(hide yes)
			)
		)
		(property "Footprint" "antmicro-footprints:C_0402_1005Metric"
			(at 316.23 66.04 0)
			(effects
				(font
					(size 1.27 1.27)
					(thickness 0.15)
				)
				(justify left bottom)
				(hide yes)
			)
		)
		(property "Datasheet" "https://www.murata.com/products/productdetail?partno=GRM155R61H104KE14%23"
			(at 313.69 66.04 0)
			(effects
				(font
					(size 1.27 1.27)
					(thickness 0.15)
				)
				(justify left bottom)
				(hide yes)
			)
		)
		(property "Description" "SMD Multilayer Ceramic Capacitor, 0.1 µF, 50 V, 0402 [1005 Metric], ± 10%, X5R, GRM Series"
			(at 328.93 86.36 0)
			(effects
				(font
					(size 1.27 1.27)
				)
				(hide yes)
			)
		)
		(property "Manufacturer" "Murata"
			(at 308.61 66.04 0)
			(effects
				(font
					(size 1.27 1.27)
					(thickness 0.15)
				)
				(justify left bottom)
				(hide yes)
			)
		)
		(property "MPN" "GRM155R61H104KE14D"
			(at 311.15 66.04 0)
			(effects
				(font
					(size 1.27 1.27)
					(thickness 0.15)
				)
				(justify left bottom)
				(hide yes)
			)
		)
		(property "Val" "100n"
			(at 331.47 85.0835 90)
			(effects
				(font
					(size 1.27 1.27)
					(thickness 0.15)
				)
				(justify left)
			)
		)
		(property "License" "Apache-2.0"
			(at 306.07 66.04 0)
			(effects
				(font
					(size 1.27 1.27)
					(thickness 0.15)
				)
				(justify left bottom)
				(hide yes)
			)
		)
		(property "Author" "Antmicro"
			(at 303.53 66.04 0)
			(effects
				(font
					(size 1.27 1.27)
					(thickness 0.15)
				)
				(justify left bottom)
				(hide yes)
			)
		)
		(property "Voltage" "50V"
			(at 300.99 66.04 0)
			(effects
				(font
					(size 1.27 1.27)
				)
				(justify left bottom)
				(hide yes)
			)
		)
		(property "Dielectric" "X5R"
			(at 298.45 66.04 0)
			(effects
				(font
					(size 1.27 1.27)
				)
				(justify left bottom)
				(hide yes)
			)
		)
		(pin "1"
		)
		(pin "2"
		)
		(instances
			(project "sdi-mipi-video-converter"
				(path ""
					(reference "C48")
					(unit 1)
				)
			)
		)
	)
	(symbol
		(lib_id "antmicropower:GND")
		(at 95.25 120.65 0)
		(mirror y)
		(unit 1)
		(exclude_from_sim no)
		(in_bom yes)
		(on_board yes)
		(dnp no)
		(fields_autoplaced yes)
		(property "Reference" "#PWR081"
			(at 86.36 123.19 0)
			(effects
				(font
					(size 1.27 1.27)
					(thickness 0.15)
				)
				(justify left bottom)
				(hide yes)
			)
		)
		(property "Value" "GND"
			(at 95.25 125.73 0)
			(effects
				(font
					(size 1.27 1.27)
					(thickness 0.15)
				)
			)
		)
		(property "Footprint" ""
			(at 86.36 128.27 0)
			(effects
				(font
					(size 1.27 1.27)
					(thickness 0.15)
				)
				(justify left bottom)
				(hide yes)
			)
		)
		(property "Datasheet" ""
			(at 86.36 133.35 0)
			(effects
				(font
					(size 1.27 1.27)
					(thickness 0.15)
				)
				(justify left bottom)
				(hide yes)
			)
		)
		(property "Description" ""
			(at 95.25 120.65 0)
			(effects
				(font
					(size 1.27 1.27)
				)
				(hide yes)
			)
		)
		(property "Author" "Antmicro"
			(at 86.36 128.27 0)
			(effects
				(font
					(size 1.27 1.27)
					(thickness 0.15)
				)
				(justify left bottom)
				(hide yes)
			)
		)
		(property "License" "Apache-2.0"
			(at 86.36 130.81 0)
			(effects
				(font
					(size 1.27 1.27)
					(thickness 0.15)
				)
				(justify left bottom)
				(hide yes)
			)
		)
		(pin "1"
		)
		(instances
			(project "sdi-mipi-video-converter"
				(path ""
					(reference "#PWR081")
					(unit 1)
				)
			)
		)
	)
	(symbol
		(lib_id "antmicroResistors0402:R_240R_0402")
		(at 251.46 119.38 90)
		(unit 1)
		(exclude_from_sim no)
		(in_bom yes)
		(on_board yes)
		(dnp no)
		(fields_autoplaced yes)
		(property "Reference" "R47"
			(at 254 115.5699 90)
			(effects
				(font
					(size 1.27 1.27)
					(thickness 0.15)
				)
				(justify right)
			)
		)
		(property "Value" "R_240R_0402"
			(at 264.16 99.06 0)
			(effects
				(font
					(size 1.27 1.27)
					(thickness 0.15)
				)
				(justify left bottom)
				(hide yes)
			)
		)
		(property "Footprint" "antmicro-footprints:R_0402_1005Metric"
			(at 266.7 99.06 0)
			(effects
				(font
					(size 1.27 1.27)
					(thickness 0.15)
				)
				(justify left bottom)
				(hide yes)
			)
		)
		(property "Datasheet" "https://www.bourns.com/docs/product-datasheets/cr.pdf"
			(at 269.24 99.06 0)
			(effects
				(font
					(size 1.27 1.27)
					(thickness 0.15)
				)
				(justify left bottom)
				(hide yes)
			)
		)
		(property "Description" "SMD Chip Resistor, 240 ohm, ± 1%, 63 mW, 0402 [1005 Metric], Thick Film, General Purpose"
			(at 251.46 119.38 0)
			(effects
				(font
					(size 1.27 1.27)
				)
				(hide yes)
			)
		)
		(property "Manufacturer" "Bourns"
			(at 274.32 99.06 0)
			(effects
				(font
					(size 1.27 1.27)
					(thickness 0.15)
				)
				(justify left bottom)
				(hide yes)
			)
		)
		(property "MPN" "CR0402-FX-2400GLF"
			(at 271.78 99.06 0)
			(effects
				(font
					(size 1.27 1.27)
					(thickness 0.15)
				)
				(justify left bottom)
				(hide yes)
			)
		)
		(property "Val" "240R"
			(at 254 118.1099 90)
			(effects
				(font
					(size 1.27 1.27)
					(thickness 0.15)
				)
				(justify right)
			)
		)
		(property "License" "Apache-2.0"
			(at 276.86 99.06 0)
			(effects
				(font
					(size 1.27 1.27)
					(thickness 0.15)
				)
				(justify left bottom)
				(hide yes)
			)
		)
		(property "Author" "Antmicro"
			(at 279.4 99.06 0)
			(effects
				(font
					(size 1.27 1.27)
					(thickness 0.15)
				)
				(justify left bottom)
				(hide yes)
			)
		)
		(property "Tolerance" "1%"
			(at 261.62 99.06 0)
			(effects
				(font
					(size 1.27 1.27)
				)
				(justify left bottom)
				(hide yes)
			)
		)
		(pin "1"
		)
		(pin "2"
		)
		(instances
			(project "sdi-mipi-video-converter"
				(path ""
					(reference "R47")
					(unit 1)
				)
			)
		)
	)
	(symbol
		(lib_id "antmicroCapacitors0402:C_100n_0402")
		(at 328.93 62.23 90)
		(unit 1)
		(exclude_from_sim no)
		(in_bom yes)
		(on_board yes)
		(dnp no)
		(fields_autoplaced yes)
		(property "Reference" "C47"
			(at 331.47 58.4135 90)
			(effects
				(font
					(size 1.27 1.27)
					(thickness 0.15)
				)
				(justify right)
			)
		)
		(property "Value" "C_100n_0402"
			(at 339.09 41.91 0)
			(effects
				(font
					(size 1.27 1.27)
					(thickness 0.15)
				)
				(justify left bottom)
				(hide yes)
			)
		)
		(property "Footprint" "antmicro-footprints:C_0402_1005Metric"
			(at 341.63 41.91 0)
			(effects
				(font
					(size 1.27 1.27)
					(thickness 0.15)
				)
				(justify left bottom)
				(hide yes)
			)
		)
		(property "Datasheet" "https://www.murata.com/products/productdetail?partno=GRM155R61H104KE14%23"
			(at 344.17 41.91 0)
			(effects
				(font
					(size 1.27 1.27)
					(thickness 0.15)
				)
				(justify left bottom)
				(hide yes)
			)
		)
		(property "Description" "SMD Multilayer Ceramic Capacitor, 0.1 µF, 50 V, 0402 [1005 Metric], ± 10%, X5R, GRM Series"
			(at 328.93 62.23 0)
			(effects
				(font
					(size 1.27 1.27)
				)
				(hide yes)
			)
		)
		(property "Manufacturer" "Murata"
			(at 349.25 41.91 0)
			(effects
				(font
					(size 1.27 1.27)
					(thickness 0.15)
				)
				(justify left bottom)
				(hide yes)
			)
		)
		(property "MPN" "GRM155R61H104KE14D"
			(at 346.71 41.91 0)
			(effects
				(font
					(size 1.27 1.27)
					(thickness 0.15)
				)
				(justify left bottom)
				(hide yes)
			)
		)
		(property "Val" "100n"
			(at 331.47 60.9535 90)
			(effects
				(font
					(size 1.27 1.27)
					(thickness 0.15)
				)
				(justify right)
			)
		)
		(property "License" "Apache-2.0"
			(at 351.79 41.91 0)
			(effects
				(font
					(size 1.27 1.27)
					(thickness 0.15)
				)
				(justify left bottom)
				(hide yes)
			)
		)
		(property "Author" "Antmicro"
			(at 354.33 41.91 0)
			(effects
				(font
					(size 1.27 1.27)
					(thickness 0.15)
				)
				(justify left bottom)
				(hide yes)
			)
		)
		(property "Voltage" "50V"
			(at 356.87 41.91 0)
			(effects
				(font
					(size 1.27 1.27)
				)
				(justify left bottom)
				(hide yes)
			)
		)
		(property "Dielectric" "X5R"
			(at 359.41 41.91 0)
			(effects
				(font
					(size 1.27 1.27)
				)
				(justify left bottom)
				(hide yes)
			)
		)
		(pin "1"
		)
		(pin "2"
		)
		(instances
			(project "sdi-mipi-video-converter"
				(path ""
					(reference "C47")
					(unit 1)
				)
			)
		)
	)
	(symbol
		(lib_id "antmicropower:GND")
		(at 307.34 87.63 0)
		(unit 1)
		(exclude_from_sim no)
		(in_bom yes)
		(on_board yes)
		(dnp no)
		(fields_autoplaced yes)
		(property "Reference" "#PWR097"
			(at 316.23 90.17 0)
			(effects
				(font
					(size 1.27 1.27)
					(thickness 0.15)
				)
				(justify left bottom)
				(hide yes)
			)
		)
		(property "Value" "GND"
			(at 307.34 92.71 0)
			(effects
				(font
					(size 1.27 1.27)
					(thickness 0.15)
				)
			)
		)
		(property "Footprint" ""
			(at 316.23 95.25 0)
			(effects
				(font
					(size 1.27 1.27)
					(thickness 0.15)
				)
				(justify left bottom)
				(hide yes)
			)
		)
		(property "Datasheet" ""
			(at 316.23 100.33 0)
			(effects
				(font
					(size 1.27 1.27)
					(thickness 0.15)
				)
				(justify left bottom)
				(hide yes)
			)
		)
		(property "Description" ""
			(at 307.34 87.63 0)
			(effects
				(font
					(size 1.27 1.27)
				)
				(hide yes)
			)
		)
		(property "Author" "Antmicro"
			(at 316.23 95.25 0)
			(effects
				(font
					(size 1.27 1.27)
					(thickness 0.15)
				)
				(justify left bottom)
				(hide yes)
			)
		)
		(property "License" "Apache-2.0"
			(at 316.23 97.79 0)
			(effects
				(font
					(size 1.27 1.27)
					(thickness 0.15)
				)
				(justify left bottom)
				(hide yes)
			)
		)
		(pin "1"
		)
		(instances
			(project "sdi-mipi-video-converter"
				(path ""
					(reference "#PWR097")
					(unit 1)
				)
			)
		)
	)
	(symbol
		(lib_id "antmicropower:GND")
		(at 125.73 165.1 0)
		(unit 1)
		(exclude_from_sim no)
		(in_bom yes)
		(on_board yes)
		(dnp no)
		(fields_autoplaced yes)
		(property "Reference" "#PWR017"
			(at 134.62 167.64 0)
			(effects
				(font
					(size 1.27 1.27)
					(thickness 0.15)
				)
				(justify left bottom)
				(hide yes)
			)
		)
		(property "Value" "GND"
			(at 125.73 170.18 0)
			(effects
				(font
					(size 1.27 1.27)
					(thickness 0.15)
				)
			)
		)
		(property "Footprint" ""
			(at 134.62 172.72 0)
			(effects
				(font
					(size 1.27 1.27)
					(thickness 0.15)
				)
				(justify left bottom)
				(hide yes)
			)
		)
		(property "Datasheet" ""
			(at 134.62 177.8 0)
			(effects
				(font
					(size 1.27 1.27)
					(thickness 0.15)
				)
				(justify left bottom)
				(hide yes)
			)
		)
		(property "Description" ""
			(at 125.73 165.1 0)
			(effects
				(font
					(size 1.27 1.27)
				)
				(hide yes)
			)
		)
		(property "Author" "Antmicro"
			(at 134.62 172.72 0)
			(effects
				(font
					(size 1.27 1.27)
					(thickness 0.15)
				)
				(justify left bottom)
				(hide yes)
			)
		)
		(property "License" "Apache-2.0"
			(at 134.62 175.26 0)
			(effects
				(font
					(size 1.27 1.27)
					(thickness 0.15)
				)
				(justify left bottom)
				(hide yes)
			)
		)
		(pin "1"
		)
		(instances
			(project "sdi-mipi-video-converter"
				(path ""
					(reference "#PWR017")
					(unit 1)
				)
			)
		)
	)
	(symbol
		(lib_id "antmicroResistorNetworksArrays:R_4x51R_0402_array")
		(at 252.73 204.47 0)
		(unit 1)
		(exclude_from_sim no)
		(in_bom yes)
		(on_board yes)
		(dnp no)
		(fields_autoplaced yes)
		(property "Reference" "R48"
			(at 257.81 198.12 0)
			(effects
				(font
					(size 1.27 1.27)
					(thickness 0.15)
				)
			)
		)
		(property "Value" "R_4x51R_0402_array"
			(at 279.4 209.55 0)
			(effects
				(font
					(size 1.27 1.27)
					(thickness 0.15)
				)
				(justify left bottom)
				(hide yes)
			)
		)
		(property "Footprint" "antmicro-footprints:R_Array_4x0402"
			(at 279.4 214.63 0)
			(effects
				(font
					(size 1.27 1.27)
					(thickness 0.15)
				)
				(justify left bottom)
				(hide yes)
			)
		)
		(property "Datasheet" "http://industrial.panasonic.com/cdbs/www-data/pdf/AOC0000/AOC0000C14.pdf"
			(at 279.4 217.17 0)
			(effects
				(font
					(size 1.27 1.27)
					(thickness 0.15)
				)
				(justify left bottom)
				(hide yes)
			)
		)
		(property "Description" "Fixed Network Resistor, 51 ohm, Isolated, 4 Resistors, 0804 [2010 Metric], Convex, ± 5%"
			(at 252.73 204.47 0)
			(effects
				(font
					(size 1.27 1.27)
				)
				(hide yes)
			)
		)
		(property "MPN" "EXB28V510JX"
			(at 279.4 219.71 0)
			(effects
				(font
					(size 1.27 1.27)
					(thickness 0.15)
				)
				(justify left bottom)
				(hide yes)
			)
		)
		(property "Manufacturer" "Panasonic"
			(at 279.4 222.25 0)
			(effects
				(font
					(size 1.27 1.27)
					(thickness 0.15)
				)
				(justify left bottom)
				(hide yes)
			)
		)
		(property "Author" "Antmicro"
			(at 279.4 224.79 0)
			(effects
				(font
					(size 1.27 1.27)
					(thickness 0.15)
				)
				(justify left bottom)
				(hide yes)
			)
		)
		(property "License" "Apache-2.0"
			(at 279.4 227.33 0)
			(effects
				(font
					(size 1.27 1.27)
					(thickness 0.15)
				)
				(justify left bottom)
				(hide yes)
			)
		)
		(property "Val" "R_4x51R_0402"
			(at 257.81 200.66 0)
			(effects
				(font
					(size 1.27 1.27)
				)
			)
		)
		(pin "1"
		)
		(pin "2"
		)
		(pin "3"
		)
		(pin "4"
		)
		(pin "5"
		)
		(pin "6"
		)
		(pin "7"
		)
		(pin "8"
		)
		(instances
			(project "sdi-mipi-video-converter"
				(path ""
					(reference "R48")
					(unit 1)
				)
			)
		)
	)
	(symbol
		(lib_id "antmicroCapacitors0402:C_100n_0402")
		(at 330.2 109.22 90)
		(unit 1)
		(exclude_from_sim no)
		(in_bom yes)
		(on_board yes)
		(dnp no)
		(fields_autoplaced yes)
		(property "Reference" "C49"
			(at 332.74 105.4035 90)
			(effects
				(font
					(size 1.27 1.27)
					(thickness 0.15)
				)
				(justify right)
			)
		)
		(property "Value" "C_100n_0402"
			(at 340.36 88.9 0)
			(effects
				(font
					(size 1.27 1.27)
					(thickness 0.15)
				)
				(justify left bottom)
				(hide yes)
			)
		)
		(property "Footprint" "antmicro-footprints:C_0402_1005Metric"
			(at 342.9 88.9 0)
			(effects
				(font
					(size 1.27 1.27)
					(thickness 0.15)
				)
				(justify left bottom)
				(hide yes)
			)
		)
		(property "Datasheet" "https://www.murata.com/products/productdetail?partno=GRM155R61H104KE14%23"
			(at 345.44 88.9 0)
			(effects
				(font
					(size 1.27 1.27)
					(thickness 0.15)
				)
				(justify left bottom)
				(hide yes)
			)
		)
		(property "Description" "SMD Multilayer Ceramic Capacitor, 0.1 µF, 50 V, 0402 [1005 Metric], ± 10%, X5R, GRM Series"
			(at 330.2 109.22 0)
			(effects
				(font
					(size 1.27 1.27)
				)
				(hide yes)
			)
		)
		(property "Manufacturer" "Murata"
			(at 350.52 88.9 0)
			(effects
				(font
					(size 1.27 1.27)
					(thickness 0.15)
				)
				(justify left bottom)
				(hide yes)
			)
		)
		(property "MPN" "GRM155R61H104KE14D"
			(at 347.98 88.9 0)
			(effects
				(font
					(size 1.27 1.27)
					(thickness 0.15)
				)
				(justify left bottom)
				(hide yes)
			)
		)
		(property "Val" "100n"
			(at 332.74 107.9435 90)
			(effects
				(font
					(size 1.27 1.27)
					(thickness 0.15)
				)
				(justify right)
			)
		)
		(property "License" "Apache-2.0"
			(at 353.06 88.9 0)
			(effects
				(font
					(size 1.27 1.27)
					(thickness 0.15)
				)
				(justify left bottom)
				(hide yes)
			)
		)
		(property "Author" "Antmicro"
			(at 355.6 88.9 0)
			(effects
				(font
					(size 1.27 1.27)
					(thickness 0.15)
				)
				(justify left bottom)
				(hide yes)
			)
		)
		(property "Voltage" "50V"
			(at 358.14 88.9 0)
			(effects
				(font
					(size 1.27 1.27)
				)
				(justify left bottom)
				(hide yes)
			)
		)
		(property "Dielectric" "X5R"
			(at 360.68 88.9 0)
			(effects
				(font
					(size 1.27 1.27)
				)
				(justify left bottom)
				(hide yes)
			)
		)
		(pin "1"
		)
		(pin "2"
		)
		(instances
			(project "sdi-mipi-video-converter"
				(path ""
					(reference "C49")
					(unit 1)
				)
			)
		)
	)
	(symbol
		(lib_id "antmicroCapacitors0402:C_100n_0402")
		(at 318.77 62.23 90)
		(unit 1)
		(exclude_from_sim no)
		(in_bom yes)
		(on_board yes)
		(dnp no)
		(fields_autoplaced yes)
		(property "Reference" "C45"
			(at 321.31 58.4135 90)
			(effects
				(font
					(size 1.27 1.27)
					(thickness 0.15)
				)
				(justify right)
			)
		)
		(property "Value" "C_100n_0402"
			(at 328.93 41.91 0)
			(effects
				(font
					(size 1.27 1.27)
					(thickness 0.15)
				)
				(justify left bottom)
				(hide yes)
			)
		)
		(property "Footprint" "antmicro-footprints:C_0402_1005Metric"
			(at 331.47 41.91 0)
			(effects
				(font
					(size 1.27 1.27)
					(thickness 0.15)
				)
				(justify left bottom)
				(hide yes)
			)
		)
		(property "Datasheet" "https://www.murata.com/products/productdetail?partno=GRM155R61H104KE14%23"
			(at 334.01 41.91 0)
			(effects
				(font
					(size 1.27 1.27)
					(thickness 0.15)
				)
				(justify left bottom)
				(hide yes)
			)
		)
		(property "Description" "SMD Multilayer Ceramic Capacitor, 0.1 µF, 50 V, 0402 [1005 Metric], ± 10%, X5R, GRM Series"
			(at 318.77 62.23 0)
			(effects
				(font
					(size 1.27 1.27)
				)
				(hide yes)
			)
		)
		(property "Manufacturer" "Murata"
			(at 339.09 41.91 0)
			(effects
				(font
					(size 1.27 1.27)
					(thickness 0.15)
				)
				(justify left bottom)
				(hide yes)
			)
		)
		(property "MPN" "GRM155R61H104KE14D"
			(at 336.55 41.91 0)
			(effects
				(font
					(size 1.27 1.27)
					(thickness 0.15)
				)
				(justify left bottom)
				(hide yes)
			)
		)
		(property "Val" "100n"
			(at 321.31 60.9535 90)
			(effects
				(font
					(size 1.27 1.27)
					(thickness 0.15)
				)
				(justify right)
			)
		)
		(property "License" "Apache-2.0"
			(at 341.63 41.91 0)
			(effects
				(font
					(size 1.27 1.27)
					(thickness 0.15)
				)
				(justify left bottom)
				(hide yes)
			)
		)
		(property "Author" "Antmicro"
			(at 344.17 41.91 0)
			(effects
				(font
					(size 1.27 1.27)
					(thickness 0.15)
				)
				(justify left bottom)
				(hide yes)
			)
		)
		(property "Voltage" "50V"
			(at 346.71 41.91 0)
			(effects
				(font
					(size 1.27 1.27)
				)
				(justify left bottom)
				(hide yes)
			)
		)
		(property "Dielectric" "X5R"
			(at 349.25 41.91 0)
			(effects
				(font
					(size 1.27 1.27)
				)
				(justify left bottom)
				(hide yes)
			)
		)
		(pin "1"
		)
		(pin "2"
		)
		(instances
			(project "sdi-mipi-video-converter"
				(path ""
					(reference "C45")
					(unit 1)
				)
			)
		)
	)
	(symbol
		(lib_id "antmicroCapacitors0402:C_100n_0402")
		(at 318.77 86.36 90)
		(unit 1)
		(exclude_from_sim no)
		(in_bom yes)
		(on_board yes)
		(dnp no)
		(fields_autoplaced yes)
		(property "Reference" "C46"
			(at 321.31 82.5435 90)
			(effects
				(font
					(size 1.27 1.27)
					(thickness 0.15)
				)
				(justify right)
			)
		)
		(property "Value" "C_100n_0402"
			(at 328.93 66.04 0)
			(effects
				(font
					(size 1.27 1.27)
					(thickness 0.15)
				)
				(justify left bottom)
				(hide yes)
			)
		)
		(property "Footprint" "antmicro-footprints:C_0402_1005Metric"
			(at 331.47 66.04 0)
			(effects
				(font
					(size 1.27 1.27)
					(thickness 0.15)
				)
				(justify left bottom)
				(hide yes)
			)
		)
		(property "Datasheet" "https://www.murata.com/products/productdetail?partno=GRM155R61H104KE14%23"
			(at 334.01 66.04 0)
			(effects
				(font
					(size 1.27 1.27)
					(thickness 0.15)
				)
				(justify left bottom)
				(hide yes)
			)
		)
		(property "Description" "SMD Multilayer Ceramic Capacitor, 0.1 µF, 50 V, 0402 [1005 Metric], ± 10%, X5R, GRM Series"
			(at 318.77 86.36 0)
			(effects
				(font
					(size 1.27 1.27)
				)
				(hide yes)
			)
		)
		(property "Manufacturer" "Murata"
			(at 339.09 66.04 0)
			(effects
				(font
					(size 1.27 1.27)
					(thickness 0.15)
				)
				(justify left bottom)
				(hide yes)
			)
		)
		(property "MPN" "GRM155R61H104KE14D"
			(at 336.55 66.04 0)
			(effects
				(font
					(size 1.27 1.27)
					(thickness 0.15)
				)
				(justify left bottom)
				(hide yes)
			)
		)
		(property "Val" "100n"
			(at 321.31 85.0835 90)
			(effects
				(font
					(size 1.27 1.27)
					(thickness 0.15)
				)
				(justify right)
			)
		)
		(property "License" "Apache-2.0"
			(at 341.63 66.04 0)
			(effects
				(font
					(size 1.27 1.27)
					(thickness 0.15)
				)
				(justify left bottom)
				(hide yes)
			)
		)
		(property "Author" "Antmicro"
			(at 344.17 66.04 0)
			(effects
				(font
					(size 1.27 1.27)
					(thickness 0.15)
				)
				(justify left bottom)
				(hide yes)
			)
		)
		(property "Voltage" "50V"
			(at 346.71 66.04 0)
			(effects
				(font
					(size 1.27 1.27)
				)
				(justify left bottom)
				(hide yes)
			)
		)
		(property "Dielectric" "X5R"
			(at 349.25 66.04 0)
			(effects
				(font
					(size 1.27 1.27)
				)
				(justify left bottom)
				(hide yes)
			)
		)
		(pin "1"
		)
		(pin "2"
		)
		(instances
			(project "sdi-mipi-video-converter"
				(path ""
					(reference "C46")
					(unit 1)
				)
			)
		)
	)
	(symbol
		(lib_id "antmicroResistorNetworksArrays:R_4x51R_0402_array")
		(at 252.73 226.06 0)
		(unit 1)
		(exclude_from_sim no)
		(in_bom yes)
		(on_board yes)
		(dnp no)
		(fields_autoplaced yes)
		(property "Reference" "R49"
			(at 257.81 219.71 0)
			(effects
				(font
					(size 1.27 1.27)
					(thickness 0.15)
				)
			)
		)
		(property "Value" "R_4x51R_0402_array"
			(at 279.4 231.14 0)
			(effects
				(font
					(size 1.27 1.27)
					(thickness 0.15)
				)
				(justify left bottom)
				(hide yes)
			)
		)
		(property "Footprint" "antmicro-footprints:R_Array_4x0402"
			(at 279.4 236.22 0)
			(effects
				(font
					(size 1.27 1.27)
					(thickness 0.15)
				)
				(justify left bottom)
				(hide yes)
			)
		)
		(property "Datasheet" "http://industrial.panasonic.com/cdbs/www-data/pdf/AOC0000/AOC0000C14.pdf"
			(at 279.4 238.76 0)
			(effects
				(font
					(size 1.27 1.27)
					(thickness 0.15)
				)
				(justify left bottom)
				(hide yes)
			)
		)
		(property "Description" "Fixed Network Resistor, 51 ohm, Isolated, 4 Resistors, 0804 [2010 Metric], Convex, ± 5%"
			(at 252.73 226.06 0)
			(effects
				(font
					(size 1.27 1.27)
				)
				(hide yes)
			)
		)
		(property "MPN" "EXB28V510JX"
			(at 279.4 241.3 0)
			(effects
				(font
					(size 1.27 1.27)
					(thickness 0.15)
				)
				(justify left bottom)
				(hide yes)
			)
		)
		(property "Manufacturer" "Panasonic"
			(at 279.4 243.84 0)
			(effects
				(font
					(size 1.27 1.27)
					(thickness 0.15)
				)
				(justify left bottom)
				(hide yes)
			)
		)
		(property "Author" "Antmicro"
			(at 279.4 246.38 0)
			(effects
				(font
					(size 1.27 1.27)
					(thickness 0.15)
				)
				(justify left bottom)
				(hide yes)
			)
		)
		(property "License" "Apache-2.0"
			(at 279.4 248.92 0)
			(effects
				(font
					(size 1.27 1.27)
					(thickness 0.15)
				)
				(justify left bottom)
				(hide yes)
			)
		)
		(property "Val" "R_4x51R_0402"
			(at 257.81 222.25 0)
			(effects
				(font
					(size 1.27 1.27)
				)
			)
		)
		(pin "1"
		)
		(pin "2"
		)
		(pin "3"
		)
		(pin "4"
		)
		(pin "5"
		)
		(pin "6"
		)
		(pin "7"
		)
		(pin "8"
		)
		(instances
			(project "sdi-mipi-video-converter"
				(path ""
					(reference "R49")
					(unit 1)
				)
			)
		)
	)
	(symbol
		(lib_id "antmicropower:GND")
		(at 328.93 63.5 0)
		(unit 1)
		(exclude_from_sim no)
		(in_bom yes)
		(on_board yes)
		(dnp no)
		(fields_autoplaced yes)
		(property "Reference" "#PWR0100"
			(at 337.82 66.04 0)
			(effects
				(font
					(size 1.27 1.27)
					(thickness 0.15)
				)
				(justify left bottom)
				(hide yes)
			)
		)
		(property "Value" "GND"
			(at 328.93 68.58 0)
			(effects
				(font
					(size 1.27 1.27)
					(thickness 0.15)
				)
			)
		)
		(property "Footprint" ""
			(at 337.82 71.12 0)
			(effects
				(font
					(size 1.27 1.27)
					(thickness 0.15)
				)
				(justify left bottom)
				(hide yes)
			)
		)
		(property "Datasheet" ""
			(at 337.82 76.2 0)
			(effects
				(font
					(size 1.27 1.27)
					(thickness 0.15)
				)
				(justify left bottom)
				(hide yes)
			)
		)
		(property "Description" ""
			(at 328.93 63.5 0)
			(effects
				(font
					(size 1.27 1.27)
				)
				(hide yes)
			)
		)
		(property "Author" "Antmicro"
			(at 337.82 71.12 0)
			(effects
				(font
					(size 1.27 1.27)
					(thickness 0.15)
				)
				(justify left bottom)
				(hide yes)
			)
		)
		(property "License" "Apache-2.0"
			(at 337.82 73.66 0)
			(effects
				(font
					(size 1.27 1.27)
					(thickness 0.15)
				)
				(justify left bottom)
				(hide yes)
			)
		)
		(pin "1"
		)
		(instances
			(project "sdi-mipi-video-converter"
				(path ""
					(reference "#PWR0100")
					(unit 1)
				)
			)
		)
	)
	(symbol
		(lib_id "antmicroCapacitors0402:C_100n_0402")
		(at 295.91 86.36 270)
		(mirror x)
		(unit 1)
		(exclude_from_sim no)
		(in_bom yes)
		(on_board yes)
		(dnp no)
		(fields_autoplaced yes)
		(property "Reference" "C42"
			(at 298.45 82.5435 90)
			(effects
				(font
					(size 1.27 1.27)
					(thickness 0.15)
				)
				(justify left)
			)
		)
		(property "Value" "C_100n_0402"
			(at 285.75 66.04 0)
			(effects
				(font
					(size 1.27 1.27)
					(thickness 0.15)
				)
				(justify left bottom)
				(hide yes)
			)
		)
		(property "Footprint" "antmicro-footprints:C_0402_1005Metric"
			(at 283.21 66.04 0)
			(effects
				(font
					(size 1.27 1.27)
					(thickness 0.15)
				)
				(justify left bottom)
				(hide yes)
			)
		)
		(property "Datasheet" "https://www.murata.com/products/productdetail?partno=GRM155R61H104KE14%23"
			(at 280.67 66.04 0)
			(effects
				(font
					(size 1.27 1.27)
					(thickness 0.15)
				)
				(justify left bottom)
				(hide yes)
			)
		)
		(property "Description" "SMD Multilayer Ceramic Capacitor, 0.1 µF, 50 V, 0402 [1005 Metric], ± 10%, X5R, GRM Series"
			(at 295.91 86.36 0)
			(effects
				(font
					(size 1.27 1.27)
				)
				(hide yes)
			)
		)
		(property "Manufacturer" "Murata"
			(at 275.59 66.04 0)
			(effects
				(font
					(size 1.27 1.27)
					(thickness 0.15)
				)
				(justify left bottom)
				(hide yes)
			)
		)
		(property "MPN" "GRM155R61H104KE14D"
			(at 278.13 66.04 0)
			(effects
				(font
					(size 1.27 1.27)
					(thickness 0.15)
				)
				(justify left bottom)
				(hide yes)
			)
		)
		(property "Val" "100n"
			(at 298.45 85.0835 90)
			(effects
				(font
					(size 1.27 1.27)
					(thickness 0.15)
				)
				(justify left)
			)
		)
		(property "License" "Apache-2.0"
			(at 273.05 66.04 0)
			(effects
				(font
					(size 1.27 1.27)
					(thickness 0.15)
				)
				(justify left bottom)
				(hide yes)
			)
		)
		(property "Author" "Antmicro"
			(at 270.51 66.04 0)
			(effects
				(font
					(size 1.27 1.27)
					(thickness 0.15)
				)
				(justify left bottom)
				(hide yes)
			)
		)
		(property "Voltage" "50V"
			(at 267.97 66.04 0)
			(effects
				(font
					(size 1.27 1.27)
				)
				(justify left bottom)
				(hide yes)
			)
		)
		(property "Dielectric" "X5R"
			(at 265.43 66.04 0)
			(effects
				(font
					(size 1.27 1.27)
				)
				(justify left bottom)
				(hide yes)
			)
		)
		(pin "1"
		)
		(pin "2"
		)
		(instances
			(project "sdi-mipi-video-converter"
				(path ""
					(reference "C42")
					(unit 1)
				)
			)
		)
	)
	(symbol
		(lib_id "antmicropower:GND")
		(at 318.77 87.63 0)
		(unit 1)
		(exclude_from_sim no)
		(in_bom yes)
		(on_board yes)
		(dnp no)
		(fields_autoplaced yes)
		(property "Reference" "#PWR099"
			(at 327.66 90.17 0)
			(effects
				(font
					(size 1.27 1.27)
					(thickness 0.15)
				)
				(justify left bottom)
				(hide yes)
			)
		)
		(property "Value" "GND"
			(at 318.77 92.71 0)
			(effects
				(font
					(size 1.27 1.27)
					(thickness 0.15)
				)
			)
		)
		(property "Footprint" ""
			(at 327.66 95.25 0)
			(effects
				(font
					(size 1.27 1.27)
					(thickness 0.15)
				)
				(justify left bottom)
				(hide yes)
			)
		)
		(property "Datasheet" ""
			(at 327.66 100.33 0)
			(effects
				(font
					(size 1.27 1.27)
					(thickness 0.15)
				)
				(justify left bottom)
				(hide yes)
			)
		)
		(property "Description" ""
			(at 318.77 87.63 0)
			(effects
				(font
					(size 1.27 1.27)
				)
				(hide yes)
			)
		)
		(property "Author" "Antmicro"
			(at 327.66 95.25 0)
			(effects
				(font
					(size 1.27 1.27)
					(thickness 0.15)
				)
				(justify left bottom)
				(hide yes)
			)
		)
		(property "License" "Apache-2.0"
			(at 327.66 97.79 0)
			(effects
				(font
					(size 1.27 1.27)
					(thickness 0.15)
				)
				(justify left bottom)
				(hide yes)
			)
		)
		(pin "1"
		)
		(instances
			(project "sdi-mipi-video-converter"
				(path ""
					(reference "#PWR099")
					(unit 1)
				)
			)
		)
	)
	(symbol
		(lib_id "antmicropower:GND")
		(at 95.25 237.49 0)
		(unit 1)
		(exclude_from_sim no)
		(in_bom yes)
		(on_board yes)
		(dnp no)
		(fields_autoplaced yes)
		(property "Reference" "#PWR082"
			(at 104.14 240.03 0)
			(effects
				(font
					(size 1.27 1.27)
					(thickness 0.15)
				)
				(justify left bottom)
				(hide yes)
			)
		)
		(property "Value" "GND"
			(at 95.25 242.57 0)
			(effects
				(font
					(size 1.27 1.27)
					(thickness 0.15)
				)
			)
		)
		(property "Footprint" ""
			(at 104.14 245.11 0)
			(effects
				(font
					(size 1.27 1.27)
					(thickness 0.15)
				)
				(justify left bottom)
				(hide yes)
			)
		)
		(property "Datasheet" ""
			(at 104.14 250.19 0)
			(effects
				(font
					(size 1.27 1.27)
					(thickness 0.15)
				)
				(justify left bottom)
				(hide yes)
			)
		)
		(property "Description" ""
			(at 95.25 237.49 0)
			(effects
				(font
					(size 1.27 1.27)
				)
				(hide yes)
			)
		)
		(property "Author" "Antmicro"
			(at 104.14 245.11 0)
			(effects
				(font
					(size 1.27 1.27)
					(thickness 0.15)
				)
				(justify left bottom)
				(hide yes)
			)
		)
		(property "License" "Apache-2.0"
			(at 104.14 247.65 0)
			(effects
				(font
					(size 1.27 1.27)
					(thickness 0.15)
				)
				(justify left bottom)
				(hide yes)
			)
		)
		(pin "1"
		)
		(instances
			(project "sdi-mipi-video-converter"
				(path ""
					(reference "#PWR082")
					(unit 1)
				)
			)
		)
	)
	(symbol
		(lib_id "antmicropower:+1V5")
		(at 295.91 77.47 0)
		(unit 1)
		(exclude_from_sim no)
		(in_bom yes)
		(on_board yes)
		(dnp no)
		(fields_autoplaced yes)
		(property "Reference" "#PWR0233"
			(at 295.91 81.28 0)
			(effects
				(font
					(size 1.27 1.27)
				)
				(hide yes)
			)
		)
		(property "Value" "+1V5"
			(at 295.91 72.39 0)
			(effects
				(font
					(size 1.27 1.27)
				)
			)
		)
		(property "Footprint" ""
			(at 295.91 77.47 0)
			(effects
				(font
					(size 1.27 1.27)
				)
				(hide yes)
			)
		)
		(property "Datasheet" ""
			(at 295.91 77.47 0)
			(effects
				(font
					(size 1.27 1.27)
				)
				(hide yes)
			)
		)
		(property "Description" ""
			(at 295.91 77.47 0)
			(effects
				(font
					(size 1.27 1.27)
				)
				(hide yes)
			)
		)
		(pin "1"
		)
		(instances
			(project "sdi-mipi-video-converter"
				(path ""
					(reference "#PWR0233")
					(unit 1)
				)
			)
		)
	)
	(symbol
		(lib_id "antmicroMemory:MT41K128M16JT-125_K")
		(at 347.98 76.2 0)
		(unit 2)
		(exclude_from_sim no)
		(in_bom yes)
		(on_board yes)
		(dnp no)
		(fields_autoplaced yes)
		(property "Reference" "U12"
			(at 367.03 82.5499 0)
			(effects
				(font
					(size 1.27 1.27)
					(thickness 0.15)
				)
				(justify left)
			)
		)
		(property "Value" "MT41K128M16JT-125_K"
			(at 367.03 85.0899 0)
			(effects
				(font
					(size 1.27 1.27)
					(thickness 0.15)
				)
				(justify left)
			)
		)
		(property "Footprint" "antmicro-footprints:BGA-96-48_8x14mm_Layout16x9_P0.8mm"
			(at 398.78 86.36 0)
			(effects
				(font
					(size 1.27 1.27)
					(thickness 0.15)
				)
				(justify left bottom)
				(hide yes)
			)
		)
		(property "Datasheet" "https://www.mouser.com/datasheet/2/671/mict_s_a0002296722_1-2290882.pdf"
			(at 398.78 88.9 0)
			(effects
				(font
					(size 1.27 1.27)
					(thickness 0.15)
				)
				(justify left bottom)
				(hide yes)
			)
		)
		(property "Description" "SDRAM - DDR3L Memory IC 2Gbit Parallel 800 MHz 13.75 ns 96-FBGA (8x14)"
			(at 347.98 76.2 0)
			(effects
				(font
					(size 1.27 1.27)
				)
				(hide yes)
			)
		)
		(property "Manufacturer" "Micron Technology"
			(at 398.78 91.44 0)
			(effects
				(font
					(size 1.27 1.27)
					(thickness 0.15)
				)
				(justify left bottom)
				(hide yes)
			)
		)
		(property "MPN" "MT41K128M16JT-125:K"
			(at 398.78 93.98 0)
			(effects
				(font
					(size 1.27 1.27)
					(thickness 0.15)
				)
				(justify left bottom)
				(hide yes)
			)
		)
		(property "Author" "Antmicro"
			(at 398.78 96.52 0)
			(effects
				(font
					(size 1.27 1.27)
					(thickness 0.15)
				)
				(justify left bottom)
				(hide yes)
			)
		)
		(property "License" "Apache-2.0"
			(at 398.78 99.06 0)
			(effects
				(font
					(size 1.27 1.27)
					(thickness 0.15)
				)
				(justify left bottom)
				(hide yes)
			)
		)
		(pin "A2"
		)
		(pin "A3"
		)
		(pin "A7"
		)
		(pin "B7"
		)
		(pin "B8"
		)
		(pin "C2"
		)
		(pin "C3"
		)
		(pin "C7"
		)
		(pin "C8"
		)
		(pin "D3"
		)
		(pin "D7"
		)
		(pin "E3"
		)
		(pin "E7"
		)
		(pin "F2"
		)
		(pin "F3"
		)
		(pin "F7"
		)
		(pin "F8"
		)
		(pin "G2"
		)
		(pin "G3"
		)
		(pin "H3"
		)
		(pin "H7"
		)
		(pin "H8"
		)
		(pin "J1"
		)
		(pin "J3"
		)
		(pin "J7"
		)
		(pin "J9"
		)
		(pin "K1"
		)
		(pin "K3"
		)
		(pin "K7"
		)
		(pin "K9"
		)
		(pin "L1"
		)
		(pin "L2"
		)
		(pin "L3"
		)
		(pin "L7"
		)
		(pin "L8"
		)
		(pin "L9"
		)
		(pin "M2"
		)
		(pin "M3"
		)
		(pin "M7"
		)
		(pin "N2"
		)
		(pin "N3"
		)
		(pin "N7"
		)
		(pin "N8"
		)
		(pin "P2"
		)
		(pin "P3"
		)
		(pin "P7"
		)
		(pin "P8"
		)
		(pin "R2"
		)
		(pin "R3"
		)
		(pin "R7"
		)
		(pin "R8"
		)
		(pin "T2"
		)
		(pin "T3"
		)
		(pin "T7"
		)
		(pin "T8"
		)
		(pin "A1"
		)
		(pin "A8"
		)
		(pin "A9"
		)
		(pin "B1"
		)
		(pin "B2"
		)
		(pin "B3"
		)
		(pin "B9"
		)
		(pin "C1"
		)
		(pin "C9"
		)
		(pin "D1"
		)
		(pin "D2"
		)
		(pin "D8"
		)
		(pin "D9"
		)
		(pin "E1"
		)
		(pin "E2"
		)
		(pin "E8"
		)
		(pin "E9"
		)
		(pin "F1"
		)
		(pin "F9"
		)
		(pin "G1"
		)
		(pin "G7"
		)
		(pin "G8"
		)
		(pin "G9"
		)
		(pin "H1"
		)
		(pin "H2"
		)
		(pin "H9"
		)
		(pin "J2"
		)
		(pin "J8"
		)
		(pin "K2"
		)
		(pin "K8"
		)
		(pin "M1"
		)
		(pin "M8"
		)
		(pin "M9"
		)
		(pin "N1"
		)
		(pin "N9"
		)
		(pin "P1"
		)
		(pin "P9"
		)
		(pin "R1"
		)
		(pin "R9"
		)
		(pin "T1"
		)
		(pin "T9"
		)
		(instances
			(project "sdi-mipi-video-converter"
				(path ""
					(reference "U12")
					(unit 2)
				)
			)
		)
	)
	(symbol
		(lib_id "antmicropower:GND")
		(at 132.08 46.99 0)
		(mirror y)
		(unit 1)
		(exclude_from_sim no)
		(in_bom yes)
		(on_board yes)
		(dnp no)
		(fields_autoplaced yes)
		(property "Reference" "#PWR090"
			(at 123.19 49.53 0)
			(effects
				(font
					(size 1.27 1.27)
					(thickness 0.15)
				)
				(justify left bottom)
				(hide yes)
			)
		)
		(property "Value" "GND"
			(at 132.08 52.07 0)
			(effects
				(font
					(size 1.27 1.27)
					(thickness 0.15)
				)
			)
		)
		(property "Footprint" ""
			(at 123.19 54.61 0)
			(effects
				(font
					(size 1.27 1.27)
					(thickness 0.15)
				)
				(justify left bottom)
				(hide yes)
			)
		)
		(property "Datasheet" ""
			(at 123.19 59.69 0)
			(effects
				(font
					(size 1.27 1.27)
					(thickness 0.15)
				)
				(justify left bottom)
				(hide yes)
			)
		)
		(property "Description" ""
			(at 132.08 46.99 0)
			(effects
				(font
					(size 1.27 1.27)
				)
				(hide yes)
			)
		)
		(property "Author" "Antmicro"
			(at 123.19 54.61 0)
			(effects
				(font
					(size 1.27 1.27)
					(thickness 0.15)
				)
				(justify left bottom)
				(hide yes)
			)
		)
		(property "License" "Apache-2.0"
			(at 123.19 57.15 0)
			(effects
				(font
					(size 1.27 1.27)
					(thickness 0.15)
				)
				(justify left bottom)
				(hide yes)
			)
		)
		(pin "1"
		)
		(instances
			(project "sdi-mipi-video-converter"
				(path ""
					(reference "#PWR090")
					(unit 1)
				)
			)
		)
	)
	(symbol
		(lib_id "antmicropower:+1V5")
		(at 295.91 53.34 0)
		(unit 1)
		(exclude_from_sim no)
		(in_bom yes)
		(on_board yes)
		(dnp no)
		(fields_autoplaced yes)
		(property "Reference" "#PWR0235"
			(at 295.91 57.15 0)
			(effects
				(font
					(size 1.27 1.27)
				)
				(hide yes)
			)
		)
		(property "Value" "+1V5"
			(at 295.91 48.26 0)
			(effects
				(font
					(size 1.27 1.27)
				)
			)
		)
		(property "Footprint" ""
			(at 295.91 53.34 0)
			(effects
				(font
					(size 1.27 1.27)
				)
				(hide yes)
			)
		)
		(property "Datasheet" ""
			(at 295.91 53.34 0)
			(effects
				(font
					(size 1.27 1.27)
				)
				(hide yes)
			)
		)
		(property "Description" ""
			(at 295.91 53.34 0)
			(effects
				(font
					(size 1.27 1.27)
				)
				(hide yes)
			)
		)
		(pin "1"
		)
		(instances
			(project "sdi-mipi-video-converter"
				(path ""
					(reference "#PWR0235")
					(unit 1)
				)
			)
		)
	)
	(symbol
		(lib_id "antmicropower:+1V5")
		(at 120.65 34.29 0)
		(unit 1)
		(exclude_from_sim no)
		(in_bom yes)
		(on_board yes)
		(dnp no)
		(fields_autoplaced yes)
		(property "Reference" "#PWR0232"
			(at 120.65 38.1 0)
			(effects
				(font
					(size 1.27 1.27)
				)
				(hide yes)
			)
		)
		(property "Value" "+1V5"
			(at 120.65 29.21 0)
			(effects
				(font
					(size 1.27 1.27)
				)
			)
		)
		(property "Footprint" ""
			(at 120.65 34.29 0)
			(effects
				(font
					(size 1.27 1.27)
				)
				(hide yes)
			)
		)
		(property "Datasheet" ""
			(at 120.65 34.29 0)
			(effects
				(font
					(size 1.27 1.27)
				)
				(hide yes)
			)
		)
		(property "Description" ""
			(at 120.65 34.29 0)
			(effects
				(font
					(size 1.27 1.27)
				)
				(hide yes)
			)
		)
		(pin "1"
		)
		(instances
			(project "sdi-mipi-video-converter"
				(path ""
					(reference "#PWR0232")
					(unit 1)
				)
			)
		)
	)
)
